G04 ================== begin FILE IDENTIFICATION RECORD ==================*
G04 Layout Name:  D:/<user>/Wistron_project/16369-sd/gbr/16369-sd.brd*
G04 Film Name:    TSILK*
G04 File Format:  Gerber RS274X*
G04 File Origin:  Cadence Allegro 16.5-S056*
G04 Origin Date:  Wed Mar 29 13:12:48 2017*
G04 *
G04 Layer:  VIA CLASS/FILMMASKTOP*
G04 Layer:  REF DES/ASSEMBLY_TOP*
G04 Layer:  PACKAGE GEOMETRY/SILKSCREEN_TOP*
G04 Layer:  DRAWING FORMAT/LAYER_PCB_STORY*
G04 Layer:  DRAWING FORMAT/LAYER_SILK_T*
G04 Layer:  BOARD GEOMETRY/SILKSCREEN_TOP*
G04 *
G04 Offset:    (0.00 0.00)*
G04 Mirror:    No*
G04 Mode:      Positive*
G04 Rotation:  0*
G04 FullContactRelief:  No*
G04 UndefLineWidth:     6.00*
G04 ================== end FILE IDENTIFICATION RECORD ====================*
%FSLAX35Y35*MOIN*%
%IR0*IPPOS*OFA0.00000B0.00000*MIA0B0*SFA1.00000B1.00000*%
%ADD10C,.01*%
%ADD11C,.02*%
%ADD12C,.012*%
%ADD13C,.013*%
%ADD14C,.015*%
%ADD15C,.016*%
%ADD16C,.006*%
%ADD17C,.008*%
G75*
%LPD*%
G75*
G36*
G01X53513Y10642D02*
X56013Y13142D01*
X51013D01*
X53513Y10642D01*
G37*
G36*
G01X51100Y64120D02*
Y94880D01*
X65700D01*
Y64120D01*
X51100D01*
G37*
G36*
G01X30300Y85100D02*
Y76300D01*
X25700D01*
Y85100D01*
X30300D01*
G37*
G36*
G01X27888Y113584D02*
X26279D01*
X27888Y115102D01*
Y113584D01*
G37*
G36*
G01X12311Y146815D02*
X9811Y144315D01*
Y149315D01*
X12311Y146815D01*
G37*
G36*
G01X12569Y164377D02*
X14269Y162677D01*
X10869D01*
X12569Y164377D01*
G37*
G36*
G01X33100Y197550D02*
X25100D01*
Y188450D01*
X33100D01*
Y197550D01*
G37*
G36*
G01X202200Y60120D02*
Y90880D01*
X216800D01*
Y60120D01*
X202200D01*
G37*
G36*
G01X183300Y84100D02*
Y75300D01*
X178700D01*
Y84100D01*
X183300D01*
G37*
G36*
G01X206364Y120732D02*
X204755D01*
X206364Y122250D01*
Y120732D01*
G37*
G36*
G01X172548Y146815D02*
X170048Y144315D01*
Y149315D01*
X172548Y146815D01*
G37*
G36*
G01X213821Y218130D02*
X215521Y216430D01*
X212121D01*
X213821Y218130D01*
G37*
G36*
G01X203500Y196650D02*
X195500D01*
Y187550D01*
X203500D01*
Y196650D01*
G37*
G54D10*
G01X6785Y227637D02*
X9185D01*
G01X179941Y280549D02*
X177541D01*
G01X512599Y275341D02*
G03Y264869I0J-5236D01*
G01Y306837D02*
G03Y296364I0J-5236D01*
G01Y338332D02*
G03Y327859I0J-5237D01*
G01Y369827D02*
G03Y359354I0J-5236D01*
G01Y401322D02*
G03Y390849I0J-5236D01*
G01Y432817D02*
G03Y422345I0J-5236D01*
G54D11*
G01X-351984Y-328833D02*
X-383984D01*
G01X-351984Y-344833D02*
Y-424833D01*
G01D02*
X998716D01*
G01X-355984Y-328833D02*
G02I-12000J0D01*
G01X-361134D02*
G02I-6850J0D01*
G01X-367984Y-344833D02*
Y-312833D01*
G01X-351984Y-344833D02*
X998716D01*
G01X-351984Y-380333D02*
X998716D01*
G01X73400Y62860D02*
X63900Y62850D01*
G01X60300Y42300D02*
X68300D01*
G01X25700Y86500D02*
X19000D01*
G01X24800Y200000D02*
X17100D01*
G01X211216Y-344833D02*
Y-424833D01*
G01X224500Y58860D02*
X215000Y58850D01*
G01X203000Y31300D02*
X211000D01*
G01X178700Y85500D02*
X172000D01*
G01X195200Y199100D02*
X187500D01*
G01X348716Y-344833D02*
Y-424833D01*
G01X463716Y-344833D02*
Y-424833D01*
G01X631216Y-344833D02*
Y-424833D01*
G01X801216Y-344833D02*
Y-424833D01*
G01X998716Y-344833D02*
Y-424833D01*
G01X1026716Y-328833D02*
G02I-12000J0D01*
G01X1021566D02*
G02I-6850J0D01*
G01X1014716Y-344833D02*
Y-312833D01*
G01X1030716Y-328833D02*
X998716D01*
G54D12*
G01X30983Y173228D02*
G02I-3700J0D01*
G01X40983D02*
G02I-3700J0D01*
G01X31159Y211023D02*
G02I-6750J0D01*
G01X31846Y222440D02*
G02I-3500J0D01*
G01X37231Y217106D02*
G02X40411Y217768I958J3366D01*
G01D02*
G02X37231Y217106I-255J-6745D01*
G01X31159Y261417D02*
G02I-6750J0D01*
G01X31846Y250000D02*
G02I-3500J0D01*
G01Y240157D02*
G02I-3500J0D01*
G01Y232283D02*
G02I-3500J0D01*
G01X37231Y255334D02*
G02X40411Y254672I2925J6083D01*
G01D02*
G02X37231Y255334I-2222J-2704D01*
G01X41689Y244094D02*
G02I-3500J0D01*
G01Y236220D02*
G02I-3500J0D01*
G01Y228346D02*
G02I-3500J0D01*
G01X46126Y303149D02*
G02I-4000J0D01*
G01X36283D02*
G02I-4000J0D01*
G01X26440D02*
G02I-4000J0D01*
G01X46126Y322835D02*
G02I-4000J0D01*
G01X36283D02*
G02I-4000J0D01*
G01X26440D02*
G02I-4000J0D01*
G01X55468Y312992D02*
G02I-3500J0D01*
G01X16098D02*
G02I-3500J0D01*
G01X137439Y78740D02*
G02I-21100J0D01*
G01X187283Y173228D02*
G02I-3700J0D01*
G01X197283D02*
G02I-3700J0D01*
G01X191396Y211023D02*
G02I-6750J0D01*
G01X192083Y222440D02*
G02I-3500J0D01*
G01X197468Y217106D02*
G02X200648Y217768I958J3366D01*
G01D02*
G02X197468Y217106I-255J-6745D01*
G01X191396Y261417D02*
G02I-6750J0D01*
G01X192083Y250000D02*
G02I-3500J0D01*
G01Y240157D02*
G02I-3500J0D01*
G01Y232283D02*
G02I-3500J0D01*
G01X197468Y255334D02*
G02X200648Y254672I2925J6083D01*
G01D02*
G02X197468Y255334I-2222J-2704D01*
G01X201926Y244094D02*
G02I-3500J0D01*
G01Y236220D02*
G02I-3500J0D01*
G01Y228346D02*
G02I-3500J0D01*
G01X206363Y303149D02*
G02I-4000J0D01*
G01X196520D02*
G02I-4000J0D01*
G01X186677D02*
G02I-4000J0D01*
G01X206363Y322835D02*
G02I-4000J0D01*
G01X196520D02*
G02I-4000J0D01*
G01X186677D02*
G02I-4000J0D01*
G01X215705Y312992D02*
G02I-3500J0D01*
G01X176335D02*
G02I-3500J0D01*
G54D13*
G01X55139Y11168D02*
X52139D01*
G01X47100Y36300D02*
X49950D01*
Y33600D01*
G01X62400Y21900D02*
X59550D01*
Y24600D01*
G01X47900Y113100D02*
Y115950D01*
X50600D01*
G01X12233Y149195D02*
Y144095D01*
G01X10069Y169327D02*
Y164327D01*
X15069D01*
G01X48583Y332042D02*
X51333D01*
Y329392D01*
G01X159602Y40682D02*
Y43532D01*
X162302D01*
G01X174600Y54400D02*
Y51550D01*
X171900D01*
G01X199200Y108100D02*
Y110950D01*
X201900D01*
G01X172470Y149195D02*
Y144095D01*
G01X211321Y223080D02*
Y218080D01*
X216321D01*
G01X208820Y332042D02*
X211570D01*
Y329392D01*
G54D14*
G01X0Y20866D02*
Y-18504D01*
G01X71407Y128987D02*
X89224Y111170D01*
G01X0Y307086D02*
Y346456D01*
G01X64567D02*
Y321260D01*
G01X0Y409449D02*
Y370079D01*
G01X71407Y517570D02*
X89224Y499752D01*
G01X0Y695669D02*
Y735039D01*
G01X64567D02*
Y709842D01*
G01X161271Y128987D02*
X143454Y111170D01*
G01X161271Y517570D02*
X143454Y499753D01*
G01X168110Y346456D02*
Y321260D01*
G01X225227Y354331D02*
X207116D01*
G01X225227Y362205D02*
X207116D01*
G01X168110Y709842D02*
Y735039D01*
G01X232677Y-18504D02*
Y20866D01*
G01X248425Y-18504D02*
Y20866D01*
G01Y346456D02*
Y307086D01*
G01X232677Y346456D02*
Y307086D01*
G01X248425Y370079D02*
Y409449D01*
G01X232677Y370079D02*
Y409449D01*
G01X255876Y354331D02*
X273986D01*
G01X255876Y362205D02*
X273986D01*
G01X232677Y735039D02*
Y695669D01*
G01X248425Y735039D02*
Y695669D01*
G01X312992Y6693D02*
Y-18504D01*
G01X337648Y216782D02*
X319832Y198966D01*
G01X312992Y395275D02*
Y370079D01*
G01X337649Y605365D02*
X319832Y587548D01*
G01X416536Y6693D02*
Y-18504D01*
G01X391880Y216782D02*
X409696Y198966D01*
G01X416536Y370079D02*
Y395275D01*
G01X391879Y605365D02*
X409696Y587548D01*
G01X481103Y20866D02*
Y-18504D01*
G01Y346456D02*
Y307086D01*
G01Y409449D02*
Y370079D01*
G01Y735039D02*
Y695669D01*
G54D15*
G01X19300Y102750D02*
X16100D01*
G01X13700Y292150D02*
X16900D01*
G01X103903Y38485D02*
Y31785D01*
G01X129915Y40791D02*
Y47491D01*
G01X195400Y117300D02*
Y114100D01*
G01X220589Y319731D02*
X223789D01*
G54D16*
G01X-322688Y-405500D02*
X-321814Y-404625D01*
X-321159Y-403167D01*
X-320722Y-401124D01*
X-321159Y-399375D01*
X-322032Y-398208D01*
X-323561Y-397333D01*
X-329456D01*
Y-414833D01*
X-322251D01*
X-320722Y-413667D01*
X-319849Y-411916D01*
X-319412Y-409875D01*
X-319849Y-407833D01*
X-321159Y-406083D01*
X-322688Y-405500D01*
X-329456D01*
G01X-309991Y-414833D02*
Y-403167D01*
G01Y-405500D02*
X-308899Y-404333D01*
X-307807Y-403458D01*
X-306279Y-403167D01*
X-305188Y-403458D01*
X-303877Y-404333D01*
G01X-294019Y-420083D02*
X-292709Y-420666D01*
X-290962Y-420083D01*
X-289871Y-418917D01*
X-288997Y-417458D01*
X-287688Y-412792D01*
X-284849Y-403167D01*
G01X-291836D02*
X-287688Y-412792D01*
G01X-268441Y-404625D02*
X-269969Y-403458D01*
X-271279Y-403167D01*
X-273026Y-403750D01*
X-274336Y-404916D01*
X-275209Y-406958D01*
X-275428Y-409000D01*
X-275209Y-411042D01*
X-274336Y-412792D01*
X-273026Y-414250D01*
X-271279Y-414833D01*
X-269751Y-414250D01*
X-268441Y-413083D01*
G01X-257709Y-406958D02*
X-250722D01*
X-251377Y-404916D01*
X-252469Y-403750D01*
X-253997Y-403167D01*
X-255526Y-403458D01*
X-256836Y-404333D01*
X-257709Y-406375D01*
X-258146Y-408125D01*
Y-409875D01*
X-257709Y-411625D01*
X-256617Y-413375D01*
X-255307Y-414541D01*
X-253779Y-414833D01*
X-252251Y-414250D01*
X-250722Y-412500D01*
G01X-214631Y-398792D02*
X-215941Y-397916D01*
X-217469Y-397333D01*
X-219216D01*
X-221181Y-398208D01*
X-222709Y-399666D01*
X-223801Y-401417D01*
X-224674Y-404333D01*
X-224893Y-406958D01*
X-224456Y-409583D01*
X-223801Y-411333D01*
X-222491Y-413083D01*
X-220962Y-414250D01*
X-219434Y-414833D01*
X-217906D01*
X-216377Y-414250D01*
X-215067Y-413375D01*
X-213975Y-412209D01*
G01X-198004Y-414833D02*
Y-403167D01*
G01Y-405208D02*
X-198877Y-404042D01*
X-200188Y-403458D01*
X-201716Y-403167D01*
X-203244Y-403750D01*
X-204554Y-404916D01*
X-205428Y-406666D01*
X-205864Y-409000D01*
X-205428Y-411333D01*
X-204554Y-413083D01*
X-203244Y-414250D01*
X-201716Y-414833D01*
X-200188Y-414541D01*
X-198877Y-413667D01*
X-198004Y-412500D01*
G01X-188146Y-414833D02*
Y-403167D01*
G01Y-406083D02*
X-187272Y-404625D01*
X-185962Y-403458D01*
X-184216Y-403167D01*
X-182688Y-403458D01*
X-181377Y-404625D01*
X-180722Y-406666D01*
Y-414833D01*
G01X-171519Y-420083D02*
X-170209Y-420666D01*
X-168462Y-420083D01*
X-167371Y-418917D01*
X-166497Y-417458D01*
X-165188Y-412792D01*
X-162349Y-403167D01*
G01X-169336D02*
X-165188Y-412792D01*
G01X-149434Y-414833D02*
X-150744Y-414541D01*
X-152054Y-413375D01*
X-152928Y-411333D01*
X-153364Y-409000D01*
X-152928Y-406666D01*
X-152054Y-404625D01*
X-150744Y-403458D01*
X-149434Y-403167D01*
X-148124Y-403458D01*
X-146814Y-404625D01*
X-145941Y-406666D01*
X-145722Y-409000D01*
X-145941Y-411333D01*
X-146814Y-413375D01*
X-148124Y-414541D01*
X-149434Y-414833D01*
G01X-135646D02*
Y-403167D01*
G01Y-406083D02*
X-134772Y-404625D01*
X-133462Y-403458D01*
X-131716Y-403167D01*
X-130188Y-403458D01*
X-128877Y-404625D01*
X-128222Y-406666D01*
Y-414833D01*
G01X-101082D02*
Y-397333D01*
X-92786D01*
G01X-95842Y-405791D02*
X-101082D01*
G01X-82491Y-414833D02*
Y-403167D01*
G01Y-405500D02*
X-81399Y-404333D01*
X-80307Y-403458D01*
X-78779Y-403167D01*
X-77688Y-403458D01*
X-76377Y-404333D01*
G01X-61934Y-414833D02*
X-63244Y-414541D01*
X-64554Y-413375D01*
X-65428Y-411333D01*
X-65864Y-409000D01*
X-65428Y-406666D01*
X-64554Y-404625D01*
X-63244Y-403458D01*
X-61934Y-403167D01*
X-60624Y-403458D01*
X-59314Y-404625D01*
X-58441Y-406666D01*
X-58222Y-409000D01*
X-58441Y-411333D01*
X-59314Y-413375D01*
X-60624Y-414541D01*
X-61934Y-414833D01*
G01X-48146D02*
Y-403167D01*
G01Y-406083D02*
X-47272Y-404625D01*
X-45962Y-403458D01*
X-44216Y-403167D01*
X-42688Y-403458D01*
X-41377Y-404625D01*
X-40722Y-406666D01*
Y-414833D01*
G01X-26934Y-397333D02*
Y-414833D01*
G01X-29991Y-403167D02*
X-23877D01*
G01X3699Y-414833D02*
Y-397333D01*
X8939D01*
X10686Y-398208D01*
X11996Y-400250D01*
X12433Y-402583D01*
X11996Y-404916D01*
X10904Y-406666D01*
X8939Y-407542D01*
X3699D01*
G01X29496Y-414833D02*
Y-403167D01*
G01Y-405208D02*
X28623Y-404042D01*
X27312Y-403458D01*
X25784Y-403167D01*
X24256Y-403750D01*
X22946Y-404916D01*
X22072Y-406666D01*
X21636Y-409000D01*
X22072Y-411333D01*
X22946Y-413083D01*
X24256Y-414250D01*
X25784Y-414833D01*
X27312Y-414541D01*
X28623Y-413667D01*
X29496Y-412500D01*
G01X39354Y-414833D02*
Y-403167D01*
G01Y-406083D02*
X40228Y-404625D01*
X41538Y-403458D01*
X43284Y-403167D01*
X44812Y-403458D01*
X46123Y-404625D01*
X46778Y-406666D01*
Y-414833D01*
G01X57291Y-406958D02*
X64278D01*
X63623Y-404916D01*
X62531Y-403750D01*
X61003Y-403167D01*
X59474Y-403458D01*
X58164Y-404333D01*
X57291Y-406375D01*
X56854Y-408125D01*
Y-409875D01*
X57291Y-411625D01*
X58383Y-413375D01*
X59693Y-414541D01*
X61221Y-414833D01*
X62749Y-414250D01*
X64278Y-412500D01*
G01X78066Y-414833D02*
Y-397333D01*
G01X114812Y-405500D02*
X115686Y-404625D01*
X116341Y-403167D01*
X116778Y-401124D01*
X116341Y-399375D01*
X115468Y-398208D01*
X113939Y-397333D01*
X108044D01*
Y-414833D01*
X115249D01*
X116778Y-413667D01*
X117651Y-411916D01*
X118088Y-409875D01*
X117651Y-407833D01*
X116341Y-406083D01*
X114812Y-405500D01*
X108044D01*
G01X130566Y-414833D02*
X129256Y-414541D01*
X127946Y-413375D01*
X127072Y-411333D01*
X126636Y-409000D01*
X127072Y-406666D01*
X127946Y-404625D01*
X129256Y-403458D01*
X130566Y-403167D01*
X131876Y-403458D01*
X133186Y-404625D01*
X134059Y-406666D01*
X134278Y-409000D01*
X134059Y-411333D01*
X133186Y-413375D01*
X131876Y-414541D01*
X130566Y-414833D01*
G01X151996D02*
Y-403167D01*
G01Y-405208D02*
X151123Y-404042D01*
X149812Y-403458D01*
X148284Y-403167D01*
X146756Y-403750D01*
X145446Y-404916D01*
X144572Y-406666D01*
X144136Y-409000D01*
X144572Y-411333D01*
X145446Y-413083D01*
X146756Y-414250D01*
X148284Y-414833D01*
X149812Y-414541D01*
X151123Y-413667D01*
X151996Y-412500D01*
G01X162509Y-414833D02*
Y-403167D01*
G01Y-405500D02*
X163601Y-404333D01*
X164693Y-403458D01*
X166221Y-403167D01*
X167312Y-403458D01*
X168623Y-404333D01*
G01X186996Y-397333D02*
Y-414833D01*
G01Y-412209D02*
X186123Y-413667D01*
X184812Y-414541D01*
X183284Y-414833D01*
X181538Y-414250D01*
X180228Y-412792D01*
X179354Y-411042D01*
X179136Y-409000D01*
X179354Y-406958D01*
X180228Y-405208D01*
X181538Y-403750D01*
X183284Y-403167D01*
X184812Y-403458D01*
X185904Y-404042D01*
X186996Y-405208D01*
G01X-111361Y-369833D02*
Y-352333D01*
X-105684Y-366916D01*
X-100007Y-352333D01*
Y-369833D01*
G01X-88184D02*
X-89494Y-369541D01*
X-90804Y-368375D01*
X-91678Y-366333D01*
X-92114Y-364000D01*
X-91678Y-361666D01*
X-90804Y-359625D01*
X-89494Y-358458D01*
X-88184Y-358167D01*
X-86874Y-358458D01*
X-85564Y-359625D01*
X-84691Y-361666D01*
X-84472Y-364000D01*
X-84691Y-366333D01*
X-85564Y-368375D01*
X-86874Y-369541D01*
X-88184Y-369833D01*
G01X-66754Y-352333D02*
Y-369833D01*
G01Y-367209D02*
X-67627Y-368667D01*
X-68938Y-369541D01*
X-70466Y-369833D01*
X-72212Y-369250D01*
X-73522Y-367792D01*
X-74396Y-366042D01*
X-74614Y-364000D01*
X-74396Y-361958D01*
X-73522Y-360208D01*
X-72212Y-358750D01*
X-70466Y-358167D01*
X-68938Y-358458D01*
X-67846Y-359042D01*
X-66754Y-360208D01*
G01X-56459Y-361958D02*
X-49472D01*
X-50127Y-359916D01*
X-51219Y-358750D01*
X-52747Y-358167D01*
X-54276Y-358458D01*
X-55586Y-359333D01*
X-56459Y-361375D01*
X-56896Y-363125D01*
Y-364875D01*
X-56459Y-366625D01*
X-55367Y-368375D01*
X-54057Y-369541D01*
X-52529Y-369833D01*
X-51001Y-369250D01*
X-49472Y-367500D01*
G01X-35684Y-369833D02*
Y-352333D01*
G01X244916Y-414833D02*
Y-397333D01*
X242296Y-400833D01*
G01Y-414833D02*
X247536D01*
G01X258268Y-407542D02*
X259796Y-405500D01*
X261106Y-404333D01*
X262853Y-403750D01*
X264381Y-404333D01*
X265473Y-405500D01*
X266346Y-407250D01*
X266564Y-409291D01*
X266346Y-411042D01*
X265473Y-412792D01*
X264162Y-414250D01*
X262634Y-414833D01*
X260888Y-414250D01*
X259359Y-412500D01*
X258486Y-409875D01*
X258268Y-406958D01*
X258704Y-403167D01*
X259359Y-401124D01*
X260451Y-399083D01*
X261979Y-397625D01*
X263508Y-397333D01*
X265036Y-397916D01*
X266128Y-399375D01*
G01X275113Y-411333D02*
X276422Y-413375D01*
X278169Y-414541D01*
X280134Y-414833D01*
X281881Y-414541D01*
X283628Y-413083D01*
X284719Y-411333D01*
X284938Y-409583D01*
X284501Y-407542D01*
X282973Y-406083D01*
X281444Y-405500D01*
X279479D01*
G01X281444D02*
X282754Y-404625D01*
X283846Y-403167D01*
X284283Y-401417D01*
X283846Y-399666D01*
X282754Y-398208D01*
X280789Y-397333D01*
X278824Y-397625D01*
X276859Y-398792D01*
G01X293268Y-407542D02*
X294796Y-405500D01*
X296106Y-404333D01*
X297853Y-403750D01*
X299381Y-404333D01*
X300473Y-405500D01*
X301346Y-407250D01*
X301564Y-409291D01*
X301346Y-411042D01*
X300473Y-412792D01*
X299162Y-414250D01*
X297634Y-414833D01*
X295888Y-414250D01*
X294359Y-412500D01*
X293486Y-409875D01*
X293268Y-406958D01*
X293704Y-403167D01*
X294359Y-401124D01*
X295451Y-399083D01*
X296979Y-397625D01*
X298508Y-397333D01*
X300036Y-397916D01*
X301128Y-399375D01*
G01X311204Y-412792D02*
X312733Y-414250D01*
X314479Y-414833D01*
X316226Y-414250D01*
X317754Y-412500D01*
X318846Y-409875D01*
X319283Y-407250D01*
Y-404042D01*
X318846Y-401417D01*
X317754Y-399083D01*
X316444Y-397916D01*
X314916Y-397333D01*
X313169Y-397916D01*
X311859Y-399083D01*
X310986Y-400833D01*
X310549Y-403167D01*
X310986Y-405208D01*
X312078Y-407250D01*
X313388Y-408417D01*
X314916Y-408708D01*
X316662Y-408125D01*
X317973Y-406666D01*
X319283Y-404042D01*
G01X231799Y-369833D02*
Y-352333D01*
X237039D01*
X238786Y-353208D01*
X240096Y-355250D01*
X240533Y-357583D01*
X240096Y-359916D01*
X239004Y-361666D01*
X237039Y-362542D01*
X231799D01*
G01X258469Y-353792D02*
X257159Y-352916D01*
X255631Y-352333D01*
X253884D01*
X251919Y-353208D01*
X250391Y-354666D01*
X249299Y-356417D01*
X248426Y-359333D01*
X248207Y-361958D01*
X248644Y-364583D01*
X249299Y-366333D01*
X250609Y-368083D01*
X252138Y-369250D01*
X253666Y-369833D01*
X255194D01*
X256723Y-369250D01*
X258033Y-368375D01*
X259125Y-367209D01*
G01X272912Y-360500D02*
X273786Y-359625D01*
X274441Y-358167D01*
X274878Y-356124D01*
X274441Y-354375D01*
X273568Y-353208D01*
X272039Y-352333D01*
X266144D01*
Y-369833D01*
X273349D01*
X274878Y-368667D01*
X275751Y-366916D01*
X276188Y-364875D01*
X275751Y-362833D01*
X274441Y-361083D01*
X272912Y-360500D01*
X266144D01*
G01X282116Y-375666D02*
X295216D01*
G01X301144Y-369833D02*
Y-352333D01*
X311188Y-369833D01*
Y-352333D01*
G01X323666Y-369833D02*
X321919Y-369541D01*
X320391Y-368375D01*
X319081Y-366625D01*
X318207Y-364583D01*
X317771Y-362250D01*
Y-359916D01*
X318207Y-357583D01*
X319081Y-355541D01*
X320391Y-353792D01*
X321919Y-352625D01*
X323666Y-352333D01*
X325412Y-352625D01*
X326941Y-353792D01*
X328251Y-355541D01*
X329125Y-357583D01*
X329561Y-359916D01*
Y-362250D01*
X329125Y-364583D01*
X328251Y-366625D01*
X326941Y-368375D01*
X325412Y-369541D01*
X323666Y-369833D01*
G01X374507Y-352333D02*
X379966Y-369833D01*
X385425Y-352333D01*
G01X401833Y-369833D02*
X393099D01*
Y-352333D01*
X401833D01*
G01X398339Y-360791D02*
X393099D01*
G01X410599Y-369833D02*
Y-352333D01*
X416058D01*
X417804Y-353208D01*
X418896Y-354375D01*
X419333Y-356708D01*
X418896Y-359042D01*
X417586Y-360500D01*
X416058Y-361375D01*
X410599D01*
G01X416058D02*
X419333Y-369833D01*
G01X432466Y-370416D02*
X432029Y-370125D01*
Y-369541D01*
X432466Y-369250D01*
X432903Y-369541D01*
Y-370125D01*
X432466Y-370416D01*
G01X392881Y-412500D02*
X394628Y-413958D01*
X396593Y-414833D01*
X398339D01*
X400086Y-413958D01*
X401396Y-412500D01*
X402051Y-410458D01*
X401614Y-408417D01*
X400523Y-406666D01*
X398558Y-405500D01*
X395938Y-404916D01*
X394409Y-403750D01*
X393754Y-401708D01*
X394191Y-399666D01*
X395283Y-398208D01*
X396811Y-397333D01*
X398339D01*
X399868Y-397916D01*
X401178Y-399375D01*
G01X410163Y-414833D02*
Y-397333D01*
X414529D01*
X416276Y-398208D01*
X417586Y-399375D01*
X418678Y-401124D01*
X419551Y-403167D01*
X419769Y-406083D01*
X419551Y-409000D01*
X418678Y-411042D01*
X417586Y-412792D01*
X416276Y-413958D01*
X414529Y-414833D01*
X410163D01*
G01X512416Y-397333D02*
Y-414833D01*
G01X507394Y-397333D02*
X517438D01*
G01X525331Y-412500D02*
X527078Y-413958D01*
X529043Y-414833D01*
X530789D01*
X532536Y-413958D01*
X533846Y-412500D01*
X534501Y-410458D01*
X534064Y-408417D01*
X532973Y-406666D01*
X531008Y-405500D01*
X528388Y-404916D01*
X526859Y-403750D01*
X526204Y-401708D01*
X526641Y-399666D01*
X527733Y-398208D01*
X529261Y-397333D01*
X530789D01*
X532318Y-397916D01*
X533628Y-399375D01*
G01X544796Y-397333D02*
X550036D01*
G01X547416D02*
Y-414833D01*
G01X544796D02*
X550036D01*
G01X560549Y-397333D02*
Y-414833D01*
X569283D01*
G01X577613D02*
Y-397333D01*
G01X585909D02*
X577613Y-408125D01*
G01X587219Y-414833D02*
X581324Y-403167D01*
G01X508049Y-352333D02*
Y-369833D01*
X516783D01*
G01X533846D02*
Y-358167D01*
G01Y-360208D02*
X532973Y-359042D01*
X531662Y-358458D01*
X530134Y-358167D01*
X528606Y-358750D01*
X527296Y-359916D01*
X526422Y-361666D01*
X525986Y-364000D01*
X526422Y-366333D01*
X527296Y-368083D01*
X528606Y-369250D01*
X530134Y-369833D01*
X531662Y-369541D01*
X532973Y-368667D01*
X533846Y-367500D01*
G01X542831Y-375083D02*
X544141Y-375666D01*
X545888Y-375083D01*
X546979Y-373917D01*
X547853Y-372458D01*
X549162Y-367792D01*
X552001Y-358167D01*
G01X545014D02*
X549162Y-367792D01*
G01X561641Y-361958D02*
X568628D01*
X567973Y-359916D01*
X566881Y-358750D01*
X565353Y-358167D01*
X563824Y-358458D01*
X562514Y-359333D01*
X561641Y-361375D01*
X561204Y-363125D01*
Y-364875D01*
X561641Y-366625D01*
X562733Y-368375D01*
X564043Y-369541D01*
X565571Y-369833D01*
X567099Y-369250D01*
X568628Y-367500D01*
G01X579359Y-369833D02*
Y-358167D01*
G01Y-360500D02*
X580451Y-359333D01*
X581543Y-358458D01*
X583071Y-358167D01*
X584162Y-358458D01*
X585473Y-359333D01*
G01X672466Y-414833D02*
X670719Y-414541D01*
X669191Y-413375D01*
X667881Y-411625D01*
X667007Y-409583D01*
X666571Y-407250D01*
Y-404916D01*
X667007Y-402583D01*
X667881Y-400541D01*
X669191Y-398792D01*
X670719Y-397625D01*
X672466Y-397333D01*
X674212Y-397625D01*
X675741Y-398792D01*
X677051Y-400541D01*
X677925Y-402583D01*
X678361Y-404916D01*
Y-407250D01*
X677925Y-409583D01*
X677051Y-411625D01*
X675741Y-413375D01*
X674212Y-414541D01*
X672466Y-414833D01*
G01X674212Y-410166D02*
X676833Y-414833D01*
G01X685163Y-397333D02*
Y-409875D01*
X686036Y-412500D01*
X687783Y-414250D01*
X689966Y-414833D01*
X692149Y-414250D01*
X693896Y-412500D01*
X694769Y-409875D01*
Y-397333D01*
G01X704846D02*
X710086D01*
G01X707466D02*
Y-414833D01*
G01X704846D02*
X710086D01*
G01X719944D02*
Y-397333D01*
X729988Y-414833D01*
Y-397333D01*
G01X747269Y-398792D02*
X745959Y-397916D01*
X744431Y-397333D01*
X742684D01*
X740719Y-398208D01*
X739191Y-399666D01*
X738099Y-401417D01*
X737226Y-404333D01*
X737007Y-406958D01*
X737444Y-409583D01*
X738099Y-411333D01*
X739409Y-413083D01*
X740938Y-414250D01*
X742466Y-414833D01*
X743994D01*
X745523Y-414250D01*
X746833Y-413375D01*
X747925Y-412209D01*
G01X759966Y-414833D02*
Y-406958D01*
X755599Y-397333D01*
G01X764333D02*
X759966Y-406958D01*
G01X650163Y-369833D02*
Y-352333D01*
X654529D01*
X656276Y-353208D01*
X657586Y-354375D01*
X658678Y-356124D01*
X659551Y-358167D01*
X659769Y-361083D01*
X659551Y-364000D01*
X658678Y-366042D01*
X657586Y-367792D01*
X656276Y-368958D01*
X654529Y-369833D01*
X650163D01*
G01X669191Y-361958D02*
X676178D01*
X675523Y-359916D01*
X674431Y-358750D01*
X672903Y-358167D01*
X671374Y-358458D01*
X670064Y-359333D01*
X669191Y-361375D01*
X668754Y-363125D01*
Y-364875D01*
X669191Y-366625D01*
X670283Y-368375D01*
X671593Y-369541D01*
X673121Y-369833D01*
X674649Y-369250D01*
X676178Y-367500D01*
G01X686691Y-367792D02*
X687783Y-368958D01*
X689311Y-369833D01*
X690621D01*
X691931Y-369250D01*
X692804Y-368375D01*
X693241Y-367209D01*
X693023Y-365458D01*
X692149Y-364583D01*
X688219Y-362833D01*
X687346Y-360791D01*
X687783Y-359333D01*
X688656Y-358458D01*
X689966Y-358167D01*
X691276Y-358458D01*
X692586Y-359333D01*
G01X707466Y-358167D02*
Y-369833D01*
G01Y-353500D02*
X707029Y-353208D01*
Y-352625D01*
X707466Y-352333D01*
X707903Y-352625D01*
Y-353208D01*
X707466Y-353500D01*
G01X721909Y-374208D02*
X723438Y-375375D01*
X725184Y-375666D01*
X726712Y-375375D01*
X728023Y-373917D01*
X728896Y-371875D01*
Y-358167D01*
G01Y-360500D02*
X728023Y-359333D01*
X726712Y-358458D01*
X725184Y-358167D01*
X723438Y-358750D01*
X722346Y-359916D01*
X721472Y-361958D01*
X721036Y-364000D01*
X721254Y-365750D01*
X722128Y-367792D01*
X723438Y-369250D01*
X725184Y-369833D01*
X726494Y-369541D01*
X728023Y-368375D01*
X728896Y-367209D01*
G01X738754Y-369833D02*
Y-358167D01*
G01Y-361083D02*
X739628Y-359625D01*
X740938Y-358458D01*
X742684Y-358167D01*
X744212Y-358458D01*
X745523Y-359625D01*
X746178Y-361666D01*
Y-369833D01*
G01X756691Y-361958D02*
X763678D01*
X763023Y-359916D01*
X761931Y-358750D01*
X760403Y-358167D01*
X758874Y-358458D01*
X757564Y-359333D01*
X756691Y-361375D01*
X756254Y-363125D01*
Y-364875D01*
X756691Y-366625D01*
X757783Y-368375D01*
X759093Y-369541D01*
X760621Y-369833D01*
X762149Y-369250D01*
X763678Y-367500D01*
G01X774409Y-369833D02*
Y-358167D01*
G01Y-360500D02*
X775501Y-359333D01*
X776593Y-358458D01*
X778121Y-358167D01*
X779212Y-358458D01*
X780523Y-359333D01*
G01X821166Y-397333D02*
X819419Y-397916D01*
X818109Y-399375D01*
X817236Y-401124D01*
X816581Y-403458D01*
X816363Y-406083D01*
X816581Y-408708D01*
X817236Y-411042D01*
X818109Y-412792D01*
X819419Y-414250D01*
X821166Y-414833D01*
X822912Y-414250D01*
X824223Y-412792D01*
X825096Y-411042D01*
X825751Y-408708D01*
X825969Y-406083D01*
X825751Y-403458D01*
X825096Y-401124D01*
X824223Y-399375D01*
X822912Y-397916D01*
X821166Y-397333D01*
G01X833863Y-411333D02*
X835172Y-413375D01*
X836919Y-414541D01*
X838884Y-414833D01*
X840631Y-414541D01*
X842378Y-413083D01*
X843469Y-411333D01*
X843688Y-409583D01*
X843251Y-407542D01*
X841723Y-406083D01*
X840194Y-405500D01*
X838229D01*
G01X840194D02*
X841504Y-404625D01*
X842596Y-403167D01*
X843033Y-401417D01*
X842596Y-399666D01*
X841504Y-398208D01*
X839539Y-397333D01*
X837574Y-397625D01*
X835609Y-398792D01*
G01X852236Y-415416D02*
X860096Y-397333D01*
G01X869518Y-400250D02*
X870828Y-398500D01*
X872356Y-397625D01*
X874103Y-397333D01*
X876286Y-397916D01*
X877814Y-399375D01*
X878251Y-401124D01*
X878033Y-402875D01*
X877159Y-404333D01*
X872793Y-407250D01*
X870828Y-409291D01*
X869518Y-412209D01*
X869081Y-414833D01*
X878251D01*
G01X887454Y-412792D02*
X888983Y-414250D01*
X890729Y-414833D01*
X892476Y-414250D01*
X894004Y-412500D01*
X895096Y-409875D01*
X895533Y-407250D01*
Y-404042D01*
X895096Y-401417D01*
X894004Y-399083D01*
X892694Y-397916D01*
X891166Y-397333D01*
X889419Y-397916D01*
X888109Y-399083D01*
X887236Y-400833D01*
X886799Y-403167D01*
X887236Y-405208D01*
X888328Y-407250D01*
X889638Y-408417D01*
X891166Y-408708D01*
X892912Y-408125D01*
X894223Y-406666D01*
X895533Y-404042D01*
G01X904736Y-415416D02*
X912596Y-397333D01*
G01X922018Y-400250D02*
X923328Y-398500D01*
X924856Y-397625D01*
X926603Y-397333D01*
X928786Y-397916D01*
X930314Y-399375D01*
X930751Y-401124D01*
X930533Y-402875D01*
X929659Y-404333D01*
X925293Y-407250D01*
X923328Y-409291D01*
X922018Y-412209D01*
X921581Y-414833D01*
X930751D01*
G01X943666Y-397333D02*
X941919Y-397916D01*
X940609Y-399375D01*
X939736Y-401124D01*
X939081Y-403458D01*
X938863Y-406083D01*
X939081Y-408708D01*
X939736Y-411042D01*
X940609Y-412792D01*
X941919Y-414250D01*
X943666Y-414833D01*
X945412Y-414250D01*
X946723Y-412792D01*
X947596Y-411042D01*
X948251Y-408708D01*
X948469Y-406083D01*
X948251Y-403458D01*
X947596Y-401124D01*
X946723Y-399375D01*
X945412Y-397916D01*
X943666Y-397333D01*
G01X961166Y-414833D02*
Y-397333D01*
X958546Y-400833D01*
G01Y-414833D02*
X963786D01*
G01X978229D02*
X978666Y-411042D01*
X979321Y-407833D01*
X980194Y-404916D01*
X981286Y-401708D01*
X983033Y-397333D01*
X974299D01*
G01X868863Y-369833D02*
Y-352333D01*
X873229D01*
X874976Y-353208D01*
X876286Y-354375D01*
X877378Y-356124D01*
X878251Y-358167D01*
X878469Y-361083D01*
X878251Y-364000D01*
X877378Y-366042D01*
X876286Y-367792D01*
X874976Y-368958D01*
X873229Y-369833D01*
X868863D01*
G01X895096D02*
Y-358167D01*
G01Y-360208D02*
X894223Y-359042D01*
X892912Y-358458D01*
X891384Y-358167D01*
X889856Y-358750D01*
X888546Y-359916D01*
X887672Y-361666D01*
X887236Y-364000D01*
X887672Y-366333D01*
X888546Y-368083D01*
X889856Y-369250D01*
X891384Y-369833D01*
X892912Y-369541D01*
X894223Y-368667D01*
X895096Y-367500D01*
G01X908666Y-352333D02*
Y-369833D01*
G01X905609Y-358167D02*
X911723D01*
G01X922891Y-361958D02*
X929878D01*
X929223Y-359916D01*
X928131Y-358750D01*
X926603Y-358167D01*
X925074Y-358458D01*
X923764Y-359333D01*
X922891Y-361375D01*
X922454Y-363125D01*
Y-364875D01*
X922891Y-366625D01*
X923983Y-368375D01*
X925293Y-369541D01*
X926821Y-369833D01*
X928349Y-369250D01*
X929878Y-367500D01*
G01X215039Y10818D02*
Y-26378D01*
X203603D01*
G02X201634Y-24410I0J1969D01*
G01Y-788D01*
G03X199666Y1181I-1968J1D01*
G01X33012D01*
G03X31044Y-788I0J-1968D01*
G01Y-24410D01*
G02X29075Y-26378I-1969J1D01*
G01X17639D01*
Y10818D01*
X215039D01*
G01X73900Y62850D02*
X52900D01*
Y94500D01*
X63900D01*
Y62850D01*
G01X55250D02*
X58400Y66000D01*
X61550Y62850D01*
G01X37883Y20200D02*
Y18408D01*
X38050Y18033D01*
X38383Y17783D01*
X38800Y17700D01*
X39217Y17783D01*
X39550Y18033D01*
X39717Y18408D01*
Y20200D01*
G01X41900Y17700D02*
Y20200D01*
X41400Y19700D01*
G01Y17700D02*
X42400D01*
G01X45000Y20200D02*
X44667Y20117D01*
X44417Y19908D01*
X44250Y19658D01*
X44125Y19325D01*
X44083Y18950D01*
X44125Y18575D01*
X44250Y18242D01*
X44417Y17992D01*
X44667Y17783D01*
X45000Y17700D01*
X45333Y17783D01*
X45583Y17992D01*
X45750Y18242D01*
X45875Y18575D01*
X45917Y18950D01*
X45875Y19325D01*
X45750Y19658D01*
X45583Y19908D01*
X45333Y20117D01*
X45000Y20200D01*
G01X39500Y22500D02*
Y35900D01*
G01X49500Y22500D02*
X39500D01*
G01X49500Y35900D02*
Y22500D01*
G01X39500Y35900D02*
X49500D01*
G01X61783Y20100D02*
Y18308D01*
X61950Y17933D01*
X62283Y17683D01*
X62700Y17600D01*
X63117Y17683D01*
X63450Y17933D01*
X63617Y18308D01*
Y20100D01*
G01X65800Y17600D02*
Y20100D01*
X65300Y19600D01*
G01Y17600D02*
X66300D01*
G01X68900D02*
Y20100D01*
X68400Y19600D01*
G01Y17600D02*
X69400D01*
G01X70000Y35700D02*
Y22300D01*
G01X60000Y35700D02*
X70000D01*
G01X60000Y22300D02*
Y35700D01*
G01X70000Y22300D02*
X60000D01*
G01X70500Y45533D02*
X72292D01*
X72667Y45700D01*
X72917Y46033D01*
X73000Y46450D01*
X72917Y46867D01*
X72667Y47200D01*
X72292Y47367D01*
X70500D01*
G01X73000Y49550D02*
X70500D01*
X71000Y49050D01*
G01X73000D02*
Y50050D01*
G01X60300Y41600D02*
X52300D01*
Y54000D01*
X60300D01*
Y41600D01*
G01X56300Y43300D02*
X54800Y41800D01*
G01X56300Y43300D02*
X57800Y41800D01*
G01X19617Y44600D02*
Y47100D01*
X20658D01*
X20992Y46975D01*
X21200Y46808D01*
X21283Y46475D01*
X21200Y46142D01*
X20950Y45933D01*
X20658Y45808D01*
X19617D01*
G01X20658D02*
X21283Y44600D01*
G01X22633Y44975D02*
X22883Y44767D01*
X23175Y44642D01*
X23550Y44600D01*
X23925Y44683D01*
X24217Y44850D01*
X24425Y45142D01*
X24467Y45475D01*
X24383Y45808D01*
X24175Y46017D01*
X23883Y46183D01*
X23592Y46225D01*
X23300Y46183D01*
X22925Y46017D01*
X23050Y47100D01*
X24175D01*
G01X38900Y60600D02*
Y64600D01*
X31500D01*
G01X37617Y53600D02*
Y56100D01*
X38658D01*
X38992Y55975D01*
X39200Y55808D01*
X39283Y55475D01*
X39200Y55142D01*
X38950Y54933D01*
X38658Y54808D01*
X37617D01*
G01X38658D02*
X39283Y53600D01*
G01X41467D02*
X41550Y54142D01*
X41675Y54600D01*
X41842Y55017D01*
X42050Y55475D01*
X42383Y56100D01*
X40717D01*
G01X53700Y57700D02*
Y61700D01*
X46300D01*
G01X8600Y70817D02*
X6100D01*
Y71858D01*
X6225Y72192D01*
X6392Y72400D01*
X6725Y72483D01*
X7058Y72400D01*
X7267Y72150D01*
X7392Y71858D01*
Y70817D01*
G01Y71858D02*
X8600Y72483D01*
G01Y75250D02*
X6100D01*
X7892Y73708D01*
Y75792D01*
G01X10100Y71800D02*
X14100D01*
Y79200D01*
G01X19867Y63600D02*
Y66100D01*
X20908D01*
X21242Y65975D01*
X21450Y65808D01*
X21533Y65475D01*
X21450Y65142D01*
X21200Y64933D01*
X20908Y64808D01*
X19867D01*
G01X20908D02*
X21533Y63600D01*
G01X22883Y63975D02*
X23133Y63767D01*
X23425Y63642D01*
X23800Y63600D01*
X24175Y63683D01*
X24467Y63850D01*
X24675Y64142D01*
X24717Y64475D01*
X24633Y64808D01*
X24425Y65017D01*
X24133Y65183D01*
X23842Y65225D01*
X23550Y65183D01*
X23175Y65017D01*
X23300Y66100D01*
X24425D01*
G01X25983Y63975D02*
X26233Y63767D01*
X26525Y63642D01*
X26900Y63600D01*
X27275Y63683D01*
X27567Y63850D01*
X27775Y64142D01*
X27817Y64475D01*
X27733Y64808D01*
X27525Y65017D01*
X27233Y65183D01*
X26942Y65225D01*
X26650Y65183D01*
X26275Y65017D01*
X26400Y66100D01*
X27525D01*
G01X35100Y68800D02*
Y72800D01*
X27700D01*
G01X6567Y66600D02*
Y69100D01*
X7608D01*
X7942Y68975D01*
X8150Y68808D01*
X8233Y68475D01*
X8150Y68142D01*
X7900Y67933D01*
X7608Y67808D01*
X6567D01*
G01X7608D02*
X8233Y66600D01*
G01X9583Y66975D02*
X9833Y66767D01*
X10125Y66642D01*
X10500Y66600D01*
X10875Y66683D01*
X11167Y66850D01*
X11375Y67142D01*
X11417Y67475D01*
X11333Y67808D01*
X11125Y68017D01*
X10833Y68183D01*
X10542Y68225D01*
X10250Y68183D01*
X9875Y68017D01*
X10000Y69100D01*
X11125D01*
G01X12808Y67642D02*
X13100Y67933D01*
X13350Y68100D01*
X13683Y68183D01*
X13975Y68100D01*
X14183Y67933D01*
X14350Y67683D01*
X14392Y67392D01*
X14350Y67142D01*
X14183Y66892D01*
X13933Y66683D01*
X13642Y66600D01*
X13308Y66683D01*
X13017Y66933D01*
X12850Y67308D01*
X12808Y67725D01*
X12892Y68267D01*
X13017Y68558D01*
X13225Y68850D01*
X13517Y69058D01*
X13808Y69100D01*
X14100Y69017D01*
X14308Y68808D01*
G01X20200Y72800D02*
Y68800D01*
X27600D01*
G01X75500Y58500D02*
Y62500D01*
X68100D01*
G01X17167Y48800D02*
Y51300D01*
X18208D01*
X18542Y51175D01*
X18750Y51008D01*
X18833Y50675D01*
X18750Y50342D01*
X18500Y50133D01*
X18208Y50008D01*
X17167D01*
G01X18208D02*
X18833Y48800D01*
G01X20308Y49842D02*
X20600Y50133D01*
X20850Y50300D01*
X21183Y50383D01*
X21475Y50300D01*
X21683Y50133D01*
X21850Y49883D01*
X21892Y49592D01*
X21850Y49342D01*
X21683Y49092D01*
X21433Y48883D01*
X21142Y48800D01*
X20808Y48883D01*
X20517Y49133D01*
X20350Y49508D01*
X20308Y49925D01*
X20392Y50467D01*
X20517Y50758D01*
X20725Y51050D01*
X21017Y51258D01*
X21308Y51300D01*
X21600Y51217D01*
X21808Y51008D01*
G01X23408Y50883D02*
X23658Y51133D01*
X23950Y51258D01*
X24283Y51300D01*
X24700Y51217D01*
X24992Y51008D01*
X25075Y50758D01*
X25033Y50508D01*
X24867Y50300D01*
X24033Y49883D01*
X23658Y49592D01*
X23408Y49175D01*
X23325Y48800D01*
X25075D01*
G01X31531Y68704D02*
Y64704D01*
X38931D01*
G01X19867Y55200D02*
Y57700D01*
X20908D01*
X21242Y57575D01*
X21450Y57408D01*
X21533Y57075D01*
X21450Y56742D01*
X21200Y56533D01*
X20908Y56408D01*
X19867D01*
G01X20908D02*
X21533Y55200D01*
G01X23008Y56242D02*
X23300Y56533D01*
X23550Y56700D01*
X23883Y56783D01*
X24175Y56700D01*
X24383Y56533D01*
X24550Y56283D01*
X24592Y55992D01*
X24550Y55742D01*
X24383Y55492D01*
X24133Y55283D01*
X23842Y55200D01*
X23508Y55283D01*
X23217Y55533D01*
X23050Y55908D01*
X23008Y56325D01*
X23092Y56867D01*
X23217Y57158D01*
X23425Y57450D01*
X23717Y57658D01*
X24008Y57700D01*
X24300Y57617D01*
X24508Y57408D01*
G01X25983Y55575D02*
X26233Y55367D01*
X26525Y55242D01*
X26900Y55200D01*
X27275Y55283D01*
X27567Y55450D01*
X27775Y55742D01*
X27817Y56075D01*
X27733Y56408D01*
X27525Y56617D01*
X27233Y56783D01*
X26942Y56825D01*
X26650Y56783D01*
X26275Y56617D01*
X26400Y57700D01*
X27525D01*
G01X42731Y68804D02*
Y72804D01*
X35331D01*
G01X58200Y21467D02*
X55700D01*
Y22508D01*
X55825Y22842D01*
X55992Y23050D01*
X56325Y23133D01*
X56658Y23050D01*
X56867Y22800D01*
X56992Y22508D01*
Y21467D01*
G01Y22508D02*
X58200Y23133D01*
G01X57825Y24483D02*
X58033Y24733D01*
X58158Y25025D01*
X58200Y25400D01*
X58117Y25775D01*
X57950Y26067D01*
X57658Y26275D01*
X57325Y26317D01*
X56992Y26233D01*
X56783Y26025D01*
X56617Y25733D01*
X56575Y25442D01*
X56617Y25150D01*
X56783Y24775D01*
X55700Y24900D01*
Y26025D01*
G01X57908Y27792D02*
X58117Y28083D01*
X58200Y28417D01*
X58117Y28750D01*
X57867Y29042D01*
X57492Y29250D01*
X57117Y29333D01*
X56658D01*
X56283Y29250D01*
X55950Y29042D01*
X55783Y28792D01*
X55700Y28500D01*
X55783Y28167D01*
X55950Y27917D01*
X56200Y27750D01*
X56533Y27667D01*
X56825Y27750D01*
X57117Y27958D01*
X57283Y28208D01*
X57325Y28500D01*
X57242Y28833D01*
X57033Y29083D01*
X56658Y29333D01*
G01X51300Y34300D02*
Y30300D01*
X58700D01*
G01X35167Y44592D02*
X34917Y44717D01*
X34625Y44800D01*
X34292D01*
X33917Y44675D01*
X33625Y44467D01*
X33417Y44217D01*
X33250Y43800D01*
X33208Y43425D01*
X33292Y43050D01*
X33417Y42800D01*
X33667Y42550D01*
X33958Y42383D01*
X34250Y42300D01*
X34542D01*
X34833Y42383D01*
X35083Y42508D01*
X35292Y42675D01*
G01X37350Y42300D02*
Y44800D01*
X36850Y44300D01*
G01Y42300D02*
X37850D01*
G01X32167Y55792D02*
X31917Y55917D01*
X31625Y56000D01*
X31292D01*
X30917Y55875D01*
X30625Y55667D01*
X30417Y55417D01*
X30250Y55000D01*
X30208Y54625D01*
X30292Y54250D01*
X30417Y54000D01*
X30667Y53750D01*
X30958Y53583D01*
X31250Y53500D01*
X31542D01*
X31833Y53583D01*
X32083Y53708D01*
X32292Y53875D01*
G01X33433D02*
X33683Y53667D01*
X33975Y53542D01*
X34350Y53500D01*
X34725Y53583D01*
X35017Y53750D01*
X35225Y54042D01*
X35267Y54375D01*
X35183Y54708D01*
X34975Y54917D01*
X34683Y55083D01*
X34392Y55125D01*
X34100Y55083D01*
X33725Y54917D01*
X33850Y56000D01*
X34975D01*
G01X53917Y19992D02*
X53667Y20117D01*
X53375Y20200D01*
X53042D01*
X52667Y20075D01*
X52375Y19867D01*
X52167Y19617D01*
X52000Y19200D01*
X51958Y18825D01*
X52042Y18450D01*
X52167Y18200D01*
X52417Y17950D01*
X52708Y17783D01*
X53000Y17700D01*
X53292D01*
X53583Y17783D01*
X53833Y17908D01*
X54042Y18075D01*
G01X55308Y19783D02*
X55558Y20033D01*
X55850Y20158D01*
X56183Y20200D01*
X56600Y20117D01*
X56892Y19908D01*
X56975Y19658D01*
X56933Y19408D01*
X56767Y19200D01*
X55933Y18783D01*
X55558Y18492D01*
X55308Y18075D01*
X55225Y17700D01*
X56975D01*
G01X59200D02*
Y20200D01*
X58700Y19700D01*
G01Y17700D02*
X59700D01*
G01X71017Y39892D02*
X70767Y40017D01*
X70475Y40100D01*
X70142D01*
X69767Y39975D01*
X69475Y39767D01*
X69267Y39517D01*
X69100Y39100D01*
X69058Y38725D01*
X69142Y38350D01*
X69267Y38100D01*
X69517Y37850D01*
X69808Y37683D01*
X70100Y37600D01*
X70392D01*
X70683Y37683D01*
X70933Y37808D01*
X71142Y37975D01*
G01X72408Y39683D02*
X72658Y39933D01*
X72950Y40058D01*
X73283Y40100D01*
X73700Y40017D01*
X73992Y39808D01*
X74075Y39558D01*
X74033Y39308D01*
X73867Y39100D01*
X73033Y38683D01*
X72658Y38392D01*
X72408Y37975D01*
X72325Y37600D01*
X74075D01*
G01X75508Y39683D02*
X75758Y39933D01*
X76050Y40058D01*
X76383Y40100D01*
X76800Y40017D01*
X77092Y39808D01*
X77175Y39558D01*
X77133Y39308D01*
X76967Y39100D01*
X76133Y38683D01*
X75758Y38392D01*
X75508Y37975D01*
X75425Y37600D01*
X77175D01*
G01X6400Y40500D02*
Y12700D01*
X34200D01*
Y40500D01*
X6400D01*
G01X55933Y100000D02*
Y98208D01*
X56100Y97833D01*
X56433Y97583D01*
X56850Y97500D01*
X57267Y97583D01*
X57600Y97833D01*
X57767Y98208D01*
Y100000D01*
G01X59158Y99583D02*
X59408Y99833D01*
X59700Y99958D01*
X60033Y100000D01*
X60450Y99917D01*
X60742Y99708D01*
X60825Y99458D01*
X60783Y99208D01*
X60617Y99000D01*
X59783Y98583D01*
X59408Y98292D01*
X59158Y97875D01*
X59075Y97500D01*
X60825D01*
G01X64183Y110700D02*
Y108908D01*
X64350Y108533D01*
X64683Y108283D01*
X65100Y108200D01*
X65517Y108283D01*
X65850Y108533D01*
X66017Y108908D01*
Y110700D01*
G01X68200Y108200D02*
Y110700D01*
X67700Y110200D01*
G01Y108200D02*
X68700D01*
G01X70383Y108575D02*
X70633Y108367D01*
X70925Y108242D01*
X71300Y108200D01*
X71675Y108283D01*
X71967Y108450D01*
X72175Y108742D01*
X72217Y109075D01*
X72133Y109408D01*
X71925Y109617D01*
X71633Y109783D01*
X71342Y109825D01*
X71050Y109783D01*
X70675Y109617D01*
X70800Y110700D01*
X71925D01*
G01X61700Y105500D02*
X48300D01*
G01X61700Y115500D02*
Y105500D01*
G01X48300Y115500D02*
X61700D01*
G01X48300Y105500D02*
Y115500D01*
G01X17992Y91363D02*
Y89571D01*
X18159Y89196D01*
X18492Y88946D01*
X18909Y88863D01*
X19326Y88946D01*
X19659Y89196D01*
X19826Y89571D01*
Y91363D01*
G01X21301Y89155D02*
X21592Y88946D01*
X21926Y88863D01*
X22259Y88946D01*
X22551Y89196D01*
X22759Y89571D01*
X22842Y89946D01*
Y90405D01*
X22759Y90780D01*
X22551Y91113D01*
X22301Y91280D01*
X22009Y91363D01*
X21676Y91280D01*
X21426Y91113D01*
X21259Y90863D01*
X21176Y90530D01*
X21259Y90238D01*
X21467Y89946D01*
X21717Y89780D01*
X22009Y89738D01*
X22342Y89821D01*
X22592Y90030D01*
X22842Y90405D01*
G01X25700Y76300D02*
Y86500D01*
G01X30300Y76300D02*
X25700D01*
G01X30300Y87200D02*
Y76300D01*
G01Y87200D02*
X19000D01*
G01X28000Y86000D02*
X29200Y87200D01*
G01X28000Y86000D02*
X26800Y87200D01*
G01X10383Y110433D02*
X7883D01*
Y111267D01*
X8008Y111600D01*
X8175Y111850D01*
X8425Y112058D01*
X8716Y112225D01*
X9133Y112267D01*
X9550Y112225D01*
X9841Y112058D01*
X10091Y111850D01*
X10258Y111600D01*
X10383Y111267D01*
Y110433D01*
G01X10091Y113742D02*
X10300Y114033D01*
X10383Y114367D01*
X10300Y114700D01*
X10050Y114992D01*
X9675Y115200D01*
X9300Y115283D01*
X8841D01*
X8466Y115200D01*
X8133Y114992D01*
X7966Y114742D01*
X7883Y114450D01*
X7966Y114117D01*
X8133Y113867D01*
X8383Y113700D01*
X8716Y113617D01*
X9008Y113700D01*
X9300Y113908D01*
X9466Y114158D01*
X9508Y114450D01*
X9425Y114783D01*
X9216Y115033D01*
X8841Y115283D01*
G01X19800Y103250D02*
X15600D01*
G01X19800Y114950D02*
Y103250D01*
G01X15600Y114950D02*
X19800D01*
G01X15600Y103250D02*
Y114950D01*
G01X39733Y115000D02*
Y113208D01*
X39900Y112833D01*
X40233Y112583D01*
X40650Y112500D01*
X41067Y112583D01*
X41400Y112833D01*
X41567Y113208D01*
Y115000D01*
G01X42833Y112875D02*
X43083Y112667D01*
X43375Y112542D01*
X43750Y112500D01*
X44125Y112583D01*
X44417Y112750D01*
X44625Y113042D01*
X44667Y113375D01*
X44583Y113708D01*
X44375Y113917D01*
X44083Y114083D01*
X43792Y114125D01*
X43500Y114083D01*
X43125Y113917D01*
X43250Y115000D01*
X44375D01*
G01X28279Y105702D02*
Y106402D01*
X27279Y107402D01*
X26579D01*
G01X32279Y105702D02*
Y106402D01*
X33279Y107402D01*
X33979D01*
G01Y113102D02*
X33279D01*
X32279Y114102D01*
Y114802D01*
G01X17167Y120700D02*
Y123200D01*
X18208D01*
X18542Y123075D01*
X18750Y122908D01*
X18833Y122575D01*
X18750Y122242D01*
X18500Y122033D01*
X18208Y121908D01*
X17167D01*
G01X18208D02*
X18833Y120700D01*
G01X21017D02*
X21100Y121242D01*
X21225Y121700D01*
X21392Y122117D01*
X21600Y122575D01*
X21933Y123200D01*
X20267D01*
G01X23283Y121075D02*
X23533Y120867D01*
X23825Y120742D01*
X24200Y120700D01*
X24575Y120783D01*
X24867Y120950D01*
X25075Y121242D01*
X25117Y121575D01*
X25033Y121908D01*
X24825Y122117D01*
X24533Y122283D01*
X24242Y122325D01*
X23950Y122283D01*
X23575Y122117D01*
X23700Y123200D01*
X24825D01*
G01X35700Y123500D02*
X31700D01*
Y116100D01*
G01X9000Y83217D02*
X6500D01*
Y84258D01*
X6625Y84592D01*
X6792Y84800D01*
X7125Y84883D01*
X7458Y84800D01*
X7667Y84550D01*
X7792Y84258D01*
Y83217D01*
G01Y84258D02*
X9000Y84883D01*
G01X7958Y86358D02*
X7667Y86650D01*
X7500Y86900D01*
X7417Y87233D01*
X7500Y87525D01*
X7667Y87733D01*
X7917Y87900D01*
X8208Y87942D01*
X8458Y87900D01*
X8708Y87733D01*
X8917Y87483D01*
X9000Y87192D01*
X8917Y86858D01*
X8667Y86567D01*
X8292Y86400D01*
X7875Y86358D01*
X7333Y86442D01*
X7042Y86567D01*
X6750Y86775D01*
X6542Y87067D01*
X6500Y87358D01*
X6583Y87650D01*
X6792Y87858D01*
G01X14100Y86700D02*
X10100D01*
Y79300D01*
G01X40800Y98167D02*
X38300D01*
Y99208D01*
X38425Y99542D01*
X38592Y99750D01*
X38925Y99833D01*
X39258Y99750D01*
X39467Y99500D01*
X39592Y99208D01*
Y98167D01*
G01Y99208D02*
X40800Y99833D01*
G01Y102600D02*
X38300D01*
X40092Y101058D01*
Y103142D01*
G01X40800Y105200D02*
X40758Y105492D01*
X40633Y105825D01*
X40425Y106033D01*
X40133Y106117D01*
X39842Y106033D01*
X39592Y105783D01*
X39467Y105408D01*
Y104992D01*
X39383Y104742D01*
X39175Y104533D01*
X38883Y104450D01*
X38592Y104575D01*
X38383Y104867D01*
X38300Y105200D01*
X38383Y105533D01*
X38592Y105825D01*
X38883Y105950D01*
X39175Y105867D01*
X39383Y105658D01*
X39467Y105408D01*
Y104992D01*
X39592Y104617D01*
X39842Y104367D01*
X40133Y104283D01*
X40425Y104367D01*
X40633Y104575D01*
X40758Y104908D01*
X40800Y105200D01*
G01X43442Y107358D02*
Y111358D01*
X36042D01*
G01X44367Y120700D02*
Y123200D01*
X45408D01*
X45742Y123075D01*
X45950Y122908D01*
X46033Y122575D01*
X45950Y122242D01*
X45700Y122033D01*
X45408Y121908D01*
X44367D01*
G01X45408D02*
X46033Y120700D01*
G01X47383Y121075D02*
X47633Y120867D01*
X47925Y120742D01*
X48300Y120700D01*
X48675Y120783D01*
X48967Y120950D01*
X49175Y121242D01*
X49217Y121575D01*
X49133Y121908D01*
X48925Y122117D01*
X48633Y122283D01*
X48342Y122325D01*
X48050Y122283D01*
X47675Y122117D01*
X47800Y123200D01*
X48925D01*
G01X51400D02*
X51067Y123117D01*
X50817Y122908D01*
X50650Y122658D01*
X50525Y122325D01*
X50483Y121950D01*
X50525Y121575D01*
X50650Y121242D01*
X50817Y120992D01*
X51067Y120783D01*
X51400Y120700D01*
X51733Y120783D01*
X51983Y120992D01*
X52150Y121242D01*
X52275Y121575D01*
X52317Y121950D01*
X52275Y122325D01*
X52150Y122658D01*
X51983Y122908D01*
X51733Y123117D01*
X51400Y123200D01*
G01X36300Y120500D02*
Y116500D01*
X43700D01*
G01X14400Y110367D02*
X11900D01*
Y111408D01*
X12025Y111742D01*
X12192Y111950D01*
X12525Y112033D01*
X12858Y111950D01*
X13067Y111700D01*
X13192Y111408D01*
Y110367D01*
G01Y111408D02*
X14400Y112033D01*
G01Y114800D02*
X11900D01*
X13692Y113258D01*
Y115342D01*
G01X14400Y117317D02*
X13858Y117400D01*
X13400Y117525D01*
X12983Y117692D01*
X12525Y117900D01*
X11900Y118233D01*
Y116567D01*
G01X21300Y103800D02*
X25300D01*
Y111200D01*
G01X5809Y120542D02*
Y123042D01*
X6850D01*
X7184Y122917D01*
X7392Y122750D01*
X7475Y122417D01*
X7392Y122084D01*
X7142Y121875D01*
X6850Y121750D01*
X5809D01*
G01X6850D02*
X7475Y120542D01*
G01X10242D02*
Y123042D01*
X8700Y121250D01*
X10784D01*
G01X12134Y120834D02*
X12425Y120625D01*
X12759Y120542D01*
X13092Y120625D01*
X13384Y120875D01*
X13592Y121250D01*
X13675Y121625D01*
Y122084D01*
X13592Y122459D01*
X13384Y122792D01*
X13134Y122959D01*
X12842Y123042D01*
X12509Y122959D01*
X12259Y122792D01*
X12092Y122542D01*
X12009Y122209D01*
X12092Y121917D01*
X12300Y121625D01*
X12550Y121459D01*
X12842Y121417D01*
X13175Y121500D01*
X13425Y121709D01*
X13675Y122084D01*
G01X30200Y123300D02*
X26200D01*
Y115900D01*
G01X29618Y94413D02*
Y96913D01*
X30659D01*
X30993Y96788D01*
X31201Y96621D01*
X31284Y96288D01*
X31201Y95955D01*
X30951Y95746D01*
X30659Y95621D01*
X29618D01*
G01X30659D02*
X31284Y94413D01*
G01X33468D02*
X33551Y94955D01*
X33676Y95413D01*
X33843Y95830D01*
X34051Y96288D01*
X34384Y96913D01*
X32718D01*
G01X36568Y94413D02*
X36651Y94955D01*
X36776Y95413D01*
X36943Y95830D01*
X37151Y96288D01*
X37484Y96913D01*
X35818D01*
G01X33800Y93400D02*
Y89400D01*
X41200D01*
G01X29117Y100692D02*
X28867Y100817D01*
X28575Y100900D01*
X28242D01*
X27867Y100775D01*
X27575Y100567D01*
X27367Y100317D01*
X27200Y99900D01*
X27158Y99525D01*
X27242Y99150D01*
X27367Y98900D01*
X27617Y98650D01*
X27908Y98483D01*
X28200Y98400D01*
X28492D01*
X28783Y98483D01*
X29033Y98608D01*
X29242Y98775D01*
G01X31300Y98400D02*
Y100900D01*
X30800Y100400D01*
G01Y98400D02*
X31800D01*
G01X33608Y100483D02*
X33858Y100733D01*
X34150Y100858D01*
X34483Y100900D01*
X34900Y100817D01*
X35192Y100608D01*
X35275Y100358D01*
X35233Y100108D01*
X35067Y99900D01*
X34233Y99483D01*
X33858Y99192D01*
X33608Y98775D01*
X33525Y98400D01*
X35275D01*
G01X11954Y91400D02*
X11829Y91150D01*
X11746Y90858D01*
Y90525D01*
X11871Y90150D01*
X12079Y89858D01*
X12329Y89650D01*
X12746Y89483D01*
X13121Y89441D01*
X13496Y89525D01*
X13746Y89650D01*
X13996Y89900D01*
X14163Y90191D01*
X14246Y90483D01*
Y90775D01*
X14163Y91066D01*
X14038Y91316D01*
X13871Y91525D01*
G01X12163Y92791D02*
X11913Y93041D01*
X11788Y93333D01*
X11746Y93666D01*
X11829Y94083D01*
X12038Y94375D01*
X12288Y94458D01*
X12538Y94416D01*
X12746Y94250D01*
X13163Y93416D01*
X13454Y93041D01*
X13871Y92791D01*
X14246Y92708D01*
Y94458D01*
G01X11746Y96683D02*
X11829Y96350D01*
X12038Y96100D01*
X12288Y95933D01*
X12621Y95808D01*
X12996Y95766D01*
X13371Y95808D01*
X13704Y95933D01*
X13954Y96100D01*
X14163Y96350D01*
X14246Y96683D01*
X14163Y97016D01*
X13954Y97266D01*
X13704Y97433D01*
X13371Y97558D01*
X12996Y97600D01*
X12621Y97558D01*
X12288Y97433D01*
X12038Y97266D01*
X11829Y97016D01*
X11746Y96683D01*
G01X63017Y119892D02*
X62767Y120017D01*
X62475Y120100D01*
X62142D01*
X61767Y119975D01*
X61475Y119767D01*
X61267Y119517D01*
X61100Y119100D01*
X61058Y118725D01*
X61142Y118350D01*
X61267Y118100D01*
X61517Y117850D01*
X61808Y117683D01*
X62100Y117600D01*
X62392D01*
X62683Y117683D01*
X62933Y117808D01*
X63142Y117975D01*
G01X64408Y119683D02*
X64658Y119933D01*
X64950Y120058D01*
X65283Y120100D01*
X65700Y120017D01*
X65992Y119808D01*
X66075Y119558D01*
X66033Y119308D01*
X65867Y119100D01*
X65033Y118683D01*
X64658Y118392D01*
X64408Y117975D01*
X64325Y117600D01*
X66075D01*
G01X68217D02*
X68300Y118142D01*
X68425Y118600D01*
X68592Y119017D01*
X68800Y119475D01*
X69133Y120100D01*
X67467D01*
G01X47017Y99692D02*
X46767Y99817D01*
X46475Y99900D01*
X46142D01*
X45767Y99775D01*
X45475Y99567D01*
X45267Y99317D01*
X45100Y98900D01*
X45058Y98525D01*
X45142Y98150D01*
X45267Y97900D01*
X45517Y97650D01*
X45808Y97483D01*
X46100Y97400D01*
X46392D01*
X46683Y97483D01*
X46933Y97608D01*
X47142Y97775D01*
G01X49200Y97400D02*
Y99900D01*
X48700Y99400D01*
G01Y97400D02*
X49700D01*
G01X51592Y97692D02*
X51883Y97483D01*
X52217Y97400D01*
X52550Y97483D01*
X52842Y97733D01*
X53050Y98108D01*
X53133Y98483D01*
Y98942D01*
X53050Y99317D01*
X52842Y99650D01*
X52592Y99817D01*
X52300Y99900D01*
X51967Y99817D01*
X51717Y99650D01*
X51550Y99400D01*
X51467Y99067D01*
X51550Y98775D01*
X51758Y98483D01*
X52008Y98317D01*
X52300Y98275D01*
X52633Y98358D01*
X52883Y98567D01*
X53133Y98942D01*
G01X6710Y137454D02*
X7043Y137246D01*
X7418Y137121D01*
X7752D01*
X8085Y137246D01*
X8335Y137454D01*
X8460Y137746D01*
X8377Y138038D01*
X8168Y138288D01*
X7793Y138454D01*
X7293Y138538D01*
X7002Y138704D01*
X6877Y138996D01*
X6960Y139288D01*
X7168Y139496D01*
X7460Y139621D01*
X7752D01*
X8043Y139538D01*
X8293Y139329D01*
G01X9435Y139621D02*
X10018Y137121D01*
X10685Y139621D01*
X11352Y137121D01*
X11935Y139621D01*
G01X12868Y137621D02*
X13118Y137329D01*
X13452Y137163D01*
X13827Y137121D01*
X14160Y137163D01*
X14493Y137371D01*
X14702Y137621D01*
X14743Y137871D01*
X14660Y138163D01*
X14368Y138371D01*
X14077Y138454D01*
X13702D01*
G01X14077D02*
X14327Y138579D01*
X14535Y138788D01*
X14618Y139038D01*
X14535Y139288D01*
X14327Y139496D01*
X13952Y139621D01*
X13577Y139579D01*
X13202Y139413D01*
G01X12583Y124595D02*
Y132495D01*
X19083D01*
Y143095D01*
X12583D01*
Y150995D01*
X51983D01*
Y143095D01*
X45483D01*
Y132495D01*
X51983D01*
Y124595D01*
X12583D01*
G01X8523Y171286D02*
X6023D01*
Y172120D01*
X6148Y172453D01*
X6315Y172703D01*
X6565Y172911D01*
X6856Y173078D01*
X7273Y173120D01*
X7690Y173078D01*
X7981Y172911D01*
X8231Y172703D01*
X8398Y172453D01*
X8523Y172120D01*
Y171286D01*
G01Y175303D02*
X6023D01*
X6523Y174803D01*
G01X8523D02*
Y175803D01*
G01X10419Y175977D02*
Y164677D01*
X18719D01*
Y175977D01*
X10419D01*
G01X40017Y166000D02*
Y163500D01*
X41683D01*
G01X44783D02*
X43117D01*
Y166000D01*
X44783D01*
G01X44117Y164792D02*
X43117D01*
G01X46133Y163500D02*
Y166000D01*
X46967D01*
X47300Y165875D01*
X47550Y165708D01*
X47758Y165458D01*
X47925Y165167D01*
X47967Y164750D01*
X47925Y164333D01*
X47758Y164042D01*
X47550Y163792D01*
X47300Y163625D01*
X46967Y163500D01*
X46133D01*
G01X50150D02*
Y166000D01*
X49650Y165500D01*
G01Y163500D02*
X50650D01*
G01X33283Y178728D02*
X35283D01*
G01X31283D02*
X29283D01*
G01X33283Y176728D02*
Y180728D01*
G01X31283Y176728D02*
Y180728D01*
X33283Y178728D01*
X31283Y176728D01*
G01X39183Y175927D02*
G02Y170529I-1900J-2699D01*
G01Y167606D01*
G02Y178850I-6900J5622D01*
G01Y175927D01*
G01X32039Y153739D02*
Y156239D01*
X33080D01*
X33414Y156114D01*
X33622Y155947D01*
X33705Y155614D01*
X33622Y155281D01*
X33372Y155072D01*
X33080Y154947D01*
X32039D01*
G01X33080D02*
X33705Y153739D01*
G01X35180Y155822D02*
X35430Y156072D01*
X35722Y156197D01*
X36055Y156239D01*
X36472Y156156D01*
X36764Y155947D01*
X36847Y155697D01*
X36805Y155447D01*
X36639Y155239D01*
X35805Y154822D01*
X35430Y154531D01*
X35180Y154114D01*
X35097Y153739D01*
X36847D01*
G01X38155Y154114D02*
X38405Y153906D01*
X38697Y153781D01*
X39072Y153739D01*
X39447Y153822D01*
X39739Y153989D01*
X39947Y154281D01*
X39989Y154614D01*
X39905Y154947D01*
X39697Y155156D01*
X39405Y155322D01*
X39114Y155364D01*
X38822Y155322D01*
X38447Y155156D01*
X38572Y156239D01*
X39697D01*
G01X5720Y184580D02*
Y182080D01*
G01X4762Y184580D02*
X6678D01*
G01X7987Y182080D02*
Y184580D01*
X8987D01*
X9320Y184455D01*
X9570Y184163D01*
X9653Y183830D01*
X9570Y183497D01*
X9362Y183247D01*
X8987Y183122D01*
X7987D01*
G01X11837Y182080D02*
X11920Y182622D01*
X12045Y183080D01*
X12212Y183497D01*
X12420Y183955D01*
X12753Y184580D01*
X11087D01*
G01X18257Y183693D02*
Y181901D01*
X18424Y181526D01*
X18757Y181276D01*
X19174Y181193D01*
X19591Y181276D01*
X19924Y181526D01*
X20091Y181901D01*
Y183693D01*
G01X22191Y181193D02*
X22274Y181735D01*
X22399Y182193D01*
X22566Y182610D01*
X22774Y183068D01*
X23107Y183693D01*
X21441D01*
G01X25100Y188750D02*
X33100D01*
Y200700D01*
X25100D01*
Y188750D01*
G01X31250Y200700D02*
X29250Y198700D01*
X27250Y200700D01*
G01X47833Y204670D02*
X16733D01*
Y267770D01*
X47833D01*
Y204670D01*
G01X12900Y214606D02*
X15400D01*
G01X12900Y213648D02*
Y215564D01*
G01X15400Y216873D02*
X12900D01*
Y217873D01*
X13025Y218206D01*
X13317Y218456D01*
X13650Y218539D01*
X13983Y218456D01*
X14233Y218248D01*
X14358Y217873D01*
Y216873D01*
G01X15400Y220806D02*
X12900D01*
X13400Y220306D01*
G01X15400D02*
Y221306D01*
G01X3645Y213473D02*
Y210973D01*
G01X2687Y213473D02*
X4603D01*
G01X5912Y210973D02*
Y213473D01*
X6912D01*
X7245Y213348D01*
X7495Y213056D01*
X7578Y212723D01*
X7495Y212390D01*
X7287Y212140D01*
X6912Y212015D01*
X5912D01*
G01X9053Y213056D02*
X9303Y213306D01*
X9595Y213431D01*
X9928Y213473D01*
X10345Y213390D01*
X10637Y213181D01*
X10720Y212931D01*
X10678Y212681D01*
X10512Y212473D01*
X9678Y212056D01*
X9303Y211765D01*
X9053Y211348D01*
X8970Y210973D01*
X10720D01*
G01X4247Y200171D02*
X1747D01*
Y201212D01*
X1872Y201546D01*
X2039Y201754D01*
X2372Y201837D01*
X2705Y201754D01*
X2914Y201504D01*
X3039Y201212D01*
Y200171D01*
G01Y201212D02*
X4247Y201837D01*
G01X3747Y203187D02*
X4039Y203437D01*
X4205Y203771D01*
X4247Y204146D01*
X4205Y204479D01*
X3997Y204812D01*
X3747Y205021D01*
X3497Y205062D01*
X3205Y204979D01*
X2997Y204687D01*
X2914Y204396D01*
Y204021D01*
G01Y204396D02*
X2789Y204646D01*
X2580Y204854D01*
X2330Y204937D01*
X2080Y204854D01*
X1872Y204646D01*
X1747Y204271D01*
X1789Y203896D01*
X1955Y203521D01*
G01X1747Y207204D02*
X1830Y206871D01*
X2039Y206621D01*
X2289Y206454D01*
X2622Y206329D01*
X2997Y206287D01*
X3372Y206329D01*
X3705Y206454D01*
X3955Y206621D01*
X4164Y206871D01*
X4247Y207204D01*
X4164Y207537D01*
X3955Y207787D01*
X3705Y207954D01*
X3372Y208079D01*
X2997Y208121D01*
X2622Y208079D01*
X2289Y207954D01*
X2039Y207787D01*
X1830Y207537D01*
X1747Y207204D01*
G01X9200Y204700D02*
X5200D01*
Y197300D01*
G01X5806Y188641D02*
X3306D01*
Y189682D01*
X3431Y190016D01*
X3598Y190224D01*
X3931Y190307D01*
X4264Y190224D01*
X4473Y189974D01*
X4598Y189682D01*
Y188641D01*
G01Y189682D02*
X5806Y190307D01*
G01X5306Y191657D02*
X5598Y191907D01*
X5764Y192241D01*
X5806Y192616D01*
X5764Y192949D01*
X5556Y193282D01*
X5306Y193491D01*
X5056Y193532D01*
X4764Y193449D01*
X4556Y193157D01*
X4473Y192866D01*
Y192491D01*
G01Y192866D02*
X4348Y193116D01*
X4139Y193324D01*
X3889Y193407D01*
X3639Y193324D01*
X3431Y193116D01*
X3306Y192741D01*
X3348Y192366D01*
X3514Y191991D01*
G01X5806Y195674D02*
X3306D01*
X3806Y195174D01*
G01X5806D02*
Y196174D01*
G01X11050Y197200D02*
X7050D01*
Y189800D01*
G01X58436Y168986D02*
X55936D01*
Y170027D01*
X56061Y170361D01*
X56228Y170569D01*
X56561Y170652D01*
X56894Y170569D01*
X57103Y170319D01*
X57228Y170027D01*
Y168986D01*
G01Y170027D02*
X58436Y170652D01*
G01X56353Y172127D02*
X56103Y172377D01*
X55978Y172669D01*
X55936Y173002D01*
X56019Y173419D01*
X56228Y173711D01*
X56478Y173794D01*
X56728Y173752D01*
X56936Y173586D01*
X57353Y172752D01*
X57644Y172377D01*
X58061Y172127D01*
X58436Y172044D01*
Y173794D01*
G01X58144Y175311D02*
X58353Y175602D01*
X58436Y175936D01*
X58353Y176269D01*
X58103Y176561D01*
X57728Y176769D01*
X57353Y176852D01*
X56894D01*
X56519Y176769D01*
X56186Y176561D01*
X56019Y176311D01*
X55936Y176019D01*
X56019Y175686D01*
X56186Y175436D01*
X56436Y175269D01*
X56769Y175186D01*
X57061Y175269D01*
X57353Y175477D01*
X57519Y175727D01*
X57561Y176019D01*
X57478Y176352D01*
X57269Y176602D01*
X56894Y176852D01*
G01X50300Y177500D02*
X46300D01*
Y170100D01*
G01X62436Y168986D02*
X59936D01*
Y170027D01*
X60061Y170361D01*
X60228Y170569D01*
X60561Y170652D01*
X60894Y170569D01*
X61103Y170319D01*
X61228Y170027D01*
Y168986D01*
G01Y170027D02*
X62436Y170652D01*
G01X61936Y172002D02*
X62228Y172252D01*
X62394Y172586D01*
X62436Y172961D01*
X62394Y173294D01*
X62186Y173627D01*
X61936Y173836D01*
X61686Y173877D01*
X61394Y173794D01*
X61186Y173502D01*
X61103Y173211D01*
Y172836D01*
G01Y173211D02*
X60978Y173461D01*
X60769Y173669D01*
X60519Y173752D01*
X60269Y173669D01*
X60061Y173461D01*
X59936Y173086D01*
X59978Y172711D01*
X60144Y172336D01*
G01X62436Y176519D02*
X59936D01*
X61728Y174977D01*
Y177061D01*
G01X50400Y170100D02*
X54400D01*
Y177500D01*
G01X50755Y208716D02*
Y211216D01*
X51796D01*
X52130Y211091D01*
X52338Y210924D01*
X52421Y210591D01*
X52338Y210258D01*
X52088Y210049D01*
X51796Y209924D01*
X50755D01*
G01X51796D02*
X52421Y208716D01*
G01X53896Y210799D02*
X54146Y211049D01*
X54438Y211174D01*
X54771Y211216D01*
X55188Y211133D01*
X55480Y210924D01*
X55563Y210674D01*
X55521Y210424D01*
X55355Y210216D01*
X54521Y209799D01*
X54146Y209508D01*
X53896Y209091D01*
X53813Y208716D01*
X55563D01*
G01X57705D02*
X57788Y209258D01*
X57913Y209716D01*
X58080Y210133D01*
X58288Y210591D01*
X58621Y211216D01*
X56955D01*
G01X50200Y189610D02*
Y193610D01*
X42800D01*
G01X50755Y205016D02*
Y207516D01*
X51796D01*
X52130Y207391D01*
X52338Y207224D01*
X52421Y206891D01*
X52338Y206558D01*
X52088Y206349D01*
X51796Y206224D01*
X50755D01*
G01X51796D02*
X52421Y205016D01*
G01X53896Y207099D02*
X54146Y207349D01*
X54438Y207474D01*
X54771Y207516D01*
X55188Y207433D01*
X55480Y207224D01*
X55563Y206974D01*
X55521Y206724D01*
X55355Y206516D01*
X54521Y206099D01*
X54146Y205808D01*
X53896Y205391D01*
X53813Y205016D01*
X55563D01*
G01X57788D02*
X58080Y205058D01*
X58413Y205183D01*
X58621Y205391D01*
X58705Y205683D01*
X58621Y205974D01*
X58371Y206224D01*
X57996Y206349D01*
X57580D01*
X57330Y206433D01*
X57121Y206641D01*
X57038Y206933D01*
X57163Y207224D01*
X57455Y207433D01*
X57788Y207516D01*
X58121Y207433D01*
X58413Y207224D01*
X58538Y206933D01*
X58455Y206641D01*
X58246Y206433D01*
X57996Y206349D01*
X57580D01*
X57205Y206224D01*
X56955Y205974D01*
X56871Y205683D01*
X56955Y205391D01*
X57163Y205183D01*
X57496Y205058D01*
X57788Y205016D01*
G01X42800Y189610D02*
Y185610D01*
X50200D01*
G01X50755Y212416D02*
Y214916D01*
X51796D01*
X52130Y214791D01*
X52338Y214624D01*
X52421Y214291D01*
X52338Y213958D01*
X52088Y213749D01*
X51796Y213624D01*
X50755D01*
G01X51796D02*
X52421Y212416D01*
G01X53771Y212916D02*
X54021Y212624D01*
X54355Y212458D01*
X54730Y212416D01*
X55063Y212458D01*
X55396Y212666D01*
X55605Y212916D01*
X55646Y213166D01*
X55563Y213458D01*
X55271Y213666D01*
X54980Y213749D01*
X54605D01*
G01X54980D02*
X55230Y213874D01*
X55438Y214083D01*
X55521Y214333D01*
X55438Y214583D01*
X55230Y214791D01*
X54855Y214916D01*
X54480Y214874D01*
X54105Y214708D01*
G01X56996Y214499D02*
X57246Y214749D01*
X57538Y214874D01*
X57871Y214916D01*
X58288Y214833D01*
X58580Y214624D01*
X58663Y214374D01*
X58621Y214124D01*
X58455Y213916D01*
X57621Y213499D01*
X57246Y213208D01*
X56996Y212791D01*
X56913Y212416D01*
X58663D01*
G01X42800Y197610D02*
Y193610D01*
X50200D01*
G01X57573Y189345D02*
X55073D01*
Y190386D01*
X55198Y190720D01*
X55365Y190928D01*
X55698Y191011D01*
X56031Y190928D01*
X56240Y190678D01*
X56365Y190386D01*
Y189345D01*
G01Y190386D02*
X57573Y191011D01*
G01X57073Y192361D02*
X57365Y192611D01*
X57531Y192945D01*
X57573Y193320D01*
X57531Y193653D01*
X57323Y193986D01*
X57073Y194195D01*
X56823Y194236D01*
X56531Y194153D01*
X56323Y193861D01*
X56240Y193570D01*
Y193195D01*
G01Y193570D02*
X56115Y193820D01*
X55906Y194028D01*
X55656Y194111D01*
X55406Y194028D01*
X55198Y193820D01*
X55073Y193445D01*
X55115Y193070D01*
X55281Y192695D01*
G01X57073Y195461D02*
X57365Y195711D01*
X57531Y196045D01*
X57573Y196420D01*
X57531Y196753D01*
X57323Y197086D01*
X57073Y197295D01*
X56823Y197336D01*
X56531Y197253D01*
X56323Y196961D01*
X56240Y196670D01*
Y196295D01*
G01Y196670D02*
X56115Y196920D01*
X55906Y197128D01*
X55656Y197211D01*
X55406Y197128D01*
X55198Y196920D01*
X55073Y196545D01*
X55115Y196170D01*
X55281Y195795D01*
G01X56492Y187324D02*
X52492D01*
Y179924D01*
G01X47767Y157067D02*
Y159567D01*
X48808D01*
X49142Y159442D01*
X49350Y159275D01*
X49433Y158942D01*
X49350Y158609D01*
X49100Y158400D01*
X48808Y158275D01*
X47767D01*
G01X48808D02*
X49433Y157067D01*
G01X50908Y159150D02*
X51158Y159400D01*
X51450Y159525D01*
X51783Y159567D01*
X52200Y159484D01*
X52492Y159275D01*
X52575Y159025D01*
X52533Y158775D01*
X52367Y158567D01*
X51533Y158150D01*
X51158Y157859D01*
X50908Y157442D01*
X50825Y157067D01*
X52575D01*
G01X54800D02*
Y159567D01*
X54300Y159067D01*
G01Y157067D02*
X55300D01*
G01X45462Y156167D02*
Y152167D01*
X52862D01*
G01X7495Y156329D02*
X7245Y156454D01*
X6953Y156537D01*
X6620D01*
X6245Y156412D01*
X5953Y156204D01*
X5745Y155954D01*
X5578Y155537D01*
X5536Y155162D01*
X5620Y154787D01*
X5745Y154537D01*
X5995Y154287D01*
X6286Y154120D01*
X6578Y154037D01*
X6870D01*
X7161Y154120D01*
X7411Y154245D01*
X7620Y154412D01*
G01X9678Y154037D02*
Y156537D01*
X9178Y156037D01*
G01Y154037D02*
X10178D01*
G01X12778D02*
Y156537D01*
X12278Y156037D01*
G01Y154037D02*
X13278D01*
G01X53659Y218555D02*
X53409Y218680D01*
X53117Y218763D01*
X52784D01*
X52409Y218638D01*
X52117Y218430D01*
X51909Y218180D01*
X51742Y217763D01*
X51700Y217388D01*
X51784Y217013D01*
X51909Y216763D01*
X52159Y216513D01*
X52450Y216346D01*
X52742Y216263D01*
X53034D01*
X53325Y216346D01*
X53575Y216471D01*
X53784Y216638D01*
G01X55842Y216263D02*
Y218763D01*
X55342Y218263D01*
G01Y216263D02*
X56342D01*
G01X59442D02*
Y218763D01*
X57900Y216971D01*
X59984D01*
G01X4917Y222188D02*
X2417D01*
Y223022D01*
X2542Y223355D01*
X2709Y223605D01*
X2959Y223813D01*
X3250Y223980D01*
X3667Y224022D01*
X4084Y223980D01*
X4375Y223813D01*
X4625Y223605D01*
X4792Y223355D01*
X4917Y223022D01*
Y222188D01*
G01X4417Y225288D02*
X4709Y225538D01*
X4875Y225872D01*
X4917Y226247D01*
X4875Y226580D01*
X4667Y226913D01*
X4417Y227122D01*
X4167Y227163D01*
X3875Y227080D01*
X3667Y226788D01*
X3584Y226497D01*
Y226122D01*
G01Y226497D02*
X3459Y226747D01*
X3250Y226955D01*
X3000Y227038D01*
X2750Y226955D01*
X2542Y226747D01*
X2417Y226372D01*
X2459Y225997D01*
X2625Y225622D01*
G01X11383Y285333D02*
X8883D01*
Y286167D01*
X9008Y286500D01*
X9175Y286750D01*
X9425Y286958D01*
X9716Y287125D01*
X10133Y287167D01*
X10550Y287125D01*
X10841Y286958D01*
X11091Y286750D01*
X11258Y286500D01*
X11383Y286167D01*
Y285333D01*
G01Y289267D02*
X10841Y289350D01*
X10383Y289475D01*
X9966Y289642D01*
X9508Y289850D01*
X8883Y290183D01*
Y288517D01*
G01X13200Y291650D02*
X17400D01*
G01X13200Y279950D02*
Y291650D01*
G01X17400Y279950D02*
X13200D01*
G01X17400Y291650D02*
Y279950D01*
G01X13117Y274992D02*
X12867Y275117D01*
X12575Y275200D01*
X12242D01*
X11867Y275075D01*
X11575Y274867D01*
X11367Y274617D01*
X11200Y274200D01*
X11158Y273825D01*
X11242Y273450D01*
X11367Y273200D01*
X11617Y272950D01*
X11908Y272783D01*
X12200Y272700D01*
X12492D01*
X12783Y272783D01*
X13033Y272908D01*
X13242Y273075D01*
G01X15300Y272700D02*
Y275200D01*
X14800Y274700D01*
G01Y272700D02*
X15800D01*
G01X17608Y273742D02*
X17900Y274033D01*
X18150Y274200D01*
X18483Y274283D01*
X18775Y274200D01*
X18983Y274033D01*
X19150Y273783D01*
X19192Y273492D01*
X19150Y273242D01*
X18983Y272992D01*
X18733Y272783D01*
X18442Y272700D01*
X18108Y272783D01*
X17817Y273033D01*
X17650Y273408D01*
X17608Y273825D01*
X17692Y274367D01*
X17817Y274658D01*
X18025Y274950D01*
X18317Y275158D01*
X18608Y275200D01*
X18900Y275117D01*
X19108Y274908D01*
G01X27200Y273000D02*
X21700D01*
Y281000D01*
X27300D01*
G01X39300Y273000D02*
X33800D01*
G01X39300D02*
Y281000D01*
X33800D01*
G01X51803Y255418D02*
X53595D01*
X53970Y255585D01*
X54220Y255918D01*
X54303Y256335D01*
X54220Y256752D01*
X53970Y257085D01*
X53595Y257252D01*
X51803D01*
G01X53970Y258560D02*
X54178Y258893D01*
X54303Y259268D01*
Y259602D01*
X54178Y259935D01*
X53970Y260185D01*
X53678Y260310D01*
X53386Y260227D01*
X53136Y260018D01*
X52970Y259643D01*
X52886Y259143D01*
X52720Y258852D01*
X52428Y258727D01*
X52136Y258810D01*
X51928Y259018D01*
X51803Y259310D01*
Y259602D01*
X51886Y259893D01*
X52095Y260143D01*
G01X52970Y262868D02*
X52845Y263035D01*
X52636Y263160D01*
X52345Y263243D01*
X52095Y263160D01*
X51928Y262993D01*
X51803Y262702D01*
Y261577D01*
X54303D01*
Y262952D01*
X54136Y263243D01*
X53886Y263410D01*
X53595Y263493D01*
X53303Y263410D01*
X53053Y263160D01*
X52970Y262868D01*
Y261577D01*
G01X54303Y265635D02*
X51803D01*
X52303Y265135D01*
G01X54303D02*
Y266135D01*
G01X30667Y287500D02*
Y290000D01*
X31708D01*
X32042Y289875D01*
X32250Y289708D01*
X32333Y289375D01*
X32250Y289042D01*
X32000Y288833D01*
X31708Y288708D01*
X30667D01*
G01X31708D02*
X32333Y287500D01*
G01X35100D02*
Y290000D01*
X33558Y288208D01*
X35642D01*
G01X36783Y287875D02*
X37033Y287667D01*
X37325Y287542D01*
X37700Y287500D01*
X38075Y287583D01*
X38367Y287750D01*
X38575Y288042D01*
X38617Y288375D01*
X38533Y288708D01*
X38325Y288917D01*
X38033Y289083D01*
X37742Y289125D01*
X37450Y289083D01*
X37075Y288917D01*
X37200Y290000D01*
X38325D01*
G01X35700Y282000D02*
Y286000D01*
X28300D01*
G01X45264Y282961D02*
X42764D01*
Y284002D01*
X42889Y284336D01*
X43056Y284544D01*
X43389Y284627D01*
X43722Y284544D01*
X43931Y284294D01*
X44056Y284002D01*
Y282961D01*
G01Y284002D02*
X45264Y284627D01*
G01Y286894D02*
X42764D01*
X43264Y286394D01*
G01X45264D02*
Y287394D01*
G01X44889Y289077D02*
X45097Y289327D01*
X45222Y289619D01*
X45264Y289994D01*
X45181Y290369D01*
X45014Y290661D01*
X44722Y290869D01*
X44389Y290911D01*
X44056Y290827D01*
X43847Y290619D01*
X43681Y290327D01*
X43639Y290036D01*
X43681Y289744D01*
X43847Y289369D01*
X42764Y289494D01*
Y290619D01*
G01X48272Y283072D02*
X52272D01*
Y290472D01*
G01X2850Y233019D02*
X5350D01*
Y234685D01*
G01Y236952D02*
X2850D01*
X3350Y236452D01*
G01X5350D02*
Y237452D01*
G01X7503Y242547D02*
Y229147D01*
G01X14703Y242547D02*
X7503D01*
G01X14703Y229147D02*
Y242547D01*
G01X7503Y229147D02*
X14703D01*
G01X9333Y270009D02*
X9083Y270134D01*
X8791Y270217D01*
X8458D01*
X8083Y270092D01*
X7791Y269884D01*
X7583Y269634D01*
X7416Y269217D01*
X7374Y268842D01*
X7458Y268467D01*
X7583Y268217D01*
X7833Y267967D01*
X8124Y267800D01*
X8416Y267717D01*
X8708D01*
X8999Y267800D01*
X9249Y267925D01*
X9458Y268092D01*
G01X10724Y269800D02*
X10974Y270050D01*
X11266Y270175D01*
X11599Y270217D01*
X12016Y270134D01*
X12308Y269925D01*
X12391Y269675D01*
X12349Y269425D01*
X12183Y269217D01*
X11349Y268800D01*
X10974Y268509D01*
X10724Y268092D01*
X10641Y267717D01*
X12391D01*
G01X9333Y266309D02*
X9083Y266434D01*
X8791Y266517D01*
X8458D01*
X8083Y266392D01*
X7791Y266184D01*
X7583Y265934D01*
X7416Y265517D01*
X7374Y265142D01*
X7458Y264767D01*
X7583Y264517D01*
X7833Y264267D01*
X8124Y264100D01*
X8416Y264017D01*
X8708D01*
X8999Y264100D01*
X9249Y264225D01*
X9458Y264392D01*
G01X10599Y264517D02*
X10849Y264225D01*
X11183Y264059D01*
X11558Y264017D01*
X11891Y264059D01*
X12224Y264267D01*
X12433Y264517D01*
X12474Y264767D01*
X12391Y265059D01*
X12099Y265267D01*
X11808Y265350D01*
X11433D01*
G01X11808D02*
X12058Y265475D01*
X12266Y265684D01*
X12349Y265934D01*
X12266Y266184D01*
X12058Y266392D01*
X11683Y266517D01*
X11308Y266475D01*
X10933Y266309D01*
G01X9333Y262609D02*
X9083Y262734D01*
X8791Y262817D01*
X8458D01*
X8083Y262692D01*
X7791Y262484D01*
X7583Y262234D01*
X7416Y261817D01*
X7374Y261442D01*
X7458Y261067D01*
X7583Y260817D01*
X7833Y260567D01*
X8124Y260400D01*
X8416Y260317D01*
X8708D01*
X8999Y260400D01*
X9249Y260525D01*
X9458Y260692D01*
G01X12016Y260317D02*
Y262817D01*
X10474Y261025D01*
X12558D01*
G01X19412Y289041D02*
X19745Y288833D01*
X20120Y288708D01*
X20454D01*
X20787Y288833D01*
X21037Y289041D01*
X21162Y289333D01*
X21079Y289625D01*
X20870Y289875D01*
X20495Y290041D01*
X19995Y290125D01*
X19704Y290291D01*
X19579Y290583D01*
X19662Y290875D01*
X19870Y291083D01*
X20162Y291208D01*
X20454D01*
X20745Y291125D01*
X20995Y290916D01*
G01X22137Y291208D02*
X22720Y288708D01*
X23387Y291208D01*
X24054Y288708D01*
X24637Y291208D01*
G01X26487Y288708D02*
Y291208D01*
X25987Y290708D01*
G01Y288708D02*
X26987D01*
G01X41160Y294292D02*
G02X23406I-8877J18700D01*
G01X13583D01*
Y304115D01*
G02X11816Y309892I18700J8878D01*
G01X9483D01*
Y316092D01*
X11816D01*
G02X13583Y321869I20467J-3101D01*
G01Y331692D01*
X23406D01*
G02X41160I8877J-18700D01*
G01X50983D01*
Y321869D01*
G02X52750Y316092I-18700J-8878D01*
G01X55083D01*
Y309892D01*
X52750D01*
G02X50983Y304115I-20467J3101D01*
G01Y294292D01*
X41160D01*
G01X32283Y317292D02*
Y314792D01*
G01X35111Y315820D02*
G02X32283Y308992I-2828J-2828D01*
G01D02*
G02X29455Y315820I0J4000D01*
G01X103082Y-6532D02*
X102549Y-6199D01*
X101949Y-5999D01*
X101415D01*
X100882Y-6199D01*
X100482Y-6532D01*
X100282Y-6999D01*
X100415Y-7466D01*
X100749Y-7866D01*
X101349Y-8132D01*
X102149Y-8266D01*
X102615Y-8532D01*
X102815Y-8999D01*
X102682Y-9466D01*
X102349Y-9799D01*
X101882Y-9999D01*
X101415D01*
X100949Y-9866D01*
X100549Y-9532D01*
G01X97082Y-5999D02*
Y-9999D01*
G01X92482Y-8666D02*
Y-5999D01*
G01Y-9732D02*
X92615Y-9799D01*
Y-9932D01*
X92482Y-9999D01*
X92349Y-9932D01*
Y-9799D01*
X92482Y-9732D01*
G01X87882Y-9999D02*
Y-5999D01*
G01X88815Y-8666D02*
X86949D01*
G01X115615Y46986D02*
X117407D01*
X117782Y47153D01*
X118032Y47486D01*
X118115Y47903D01*
X118032Y48320D01*
X117782Y48653D01*
X117407Y48820D01*
X115615D01*
G01X118115Y51003D02*
X115615D01*
X116115Y50503D01*
G01X118115D02*
Y51503D01*
G01X117823Y53395D02*
X118032Y53686D01*
X118115Y54020D01*
X118032Y54353D01*
X117782Y54645D01*
X117407Y54853D01*
X117032Y54936D01*
X116573D01*
X116198Y54853D01*
X115865Y54645D01*
X115698Y54395D01*
X115615Y54103D01*
X115698Y53770D01*
X115865Y53520D01*
X116115Y53353D01*
X116448Y53270D01*
X116740Y53353D01*
X117032Y53561D01*
X117198Y53811D01*
X117240Y54103D01*
X117157Y54436D01*
X116948Y54686D01*
X116573Y54936D01*
G01X104053Y41685D02*
X104203D01*
X105453Y40435D01*
X104253Y39235D01*
X104003D01*
G01X104053Y31685D02*
Y48885D01*
X113953D01*
Y31685D01*
X104053D01*
G01X115591Y36268D02*
X117383D01*
X117758Y36435D01*
X118008Y36768D01*
X118091Y37185D01*
X118008Y37602D01*
X117758Y37935D01*
X117383Y38102D01*
X115591D01*
G01X116008Y39493D02*
X115758Y39743D01*
X115633Y40035D01*
X115591Y40368D01*
X115674Y40785D01*
X115883Y41077D01*
X116133Y41160D01*
X116383Y41118D01*
X116591Y40952D01*
X117008Y40118D01*
X117299Y39743D01*
X117716Y39493D01*
X118091Y39410D01*
Y41160D01*
G01X115591Y43385D02*
X115674Y43052D01*
X115883Y42802D01*
X116133Y42635D01*
X116466Y42510D01*
X116841Y42468D01*
X117216Y42510D01*
X117549Y42635D01*
X117799Y42802D01*
X118008Y43052D01*
X118091Y43385D01*
X118008Y43718D01*
X117799Y43968D01*
X117549Y44135D01*
X117216Y44260D01*
X116841Y44302D01*
X116466Y44260D01*
X116133Y44135D01*
X115883Y43968D01*
X115674Y43718D01*
X115591Y43385D01*
G01X129765Y37591D02*
X129615D01*
X128365Y38841D01*
X129565Y40041D01*
X129815D01*
G01X129765Y47591D02*
Y30391D01*
X119865D01*
Y47591D01*
X129765D01*
G01X94119Y24124D02*
Y26624D01*
X95160D01*
X95494Y26499D01*
X95702Y26332D01*
X95785Y25999D01*
X95702Y25666D01*
X95452Y25457D01*
X95160Y25332D01*
X94119D01*
G01X95160D02*
X95785Y24124D01*
G01X98052D02*
Y26624D01*
X97552Y26124D01*
G01Y24124D02*
X98552D01*
G01X100360Y25166D02*
X100652Y25457D01*
X100902Y25624D01*
X101235Y25707D01*
X101527Y25624D01*
X101735Y25457D01*
X101902Y25207D01*
X101944Y24916D01*
X101902Y24666D01*
X101735Y24416D01*
X101485Y24207D01*
X101194Y24124D01*
X100860Y24207D01*
X100569Y24457D01*
X100402Y24832D01*
X100360Y25249D01*
X100444Y25791D01*
X100569Y26082D01*
X100777Y26374D01*
X101069Y26582D01*
X101360Y26624D01*
X101652Y26541D01*
X101860Y26332D01*
G01X106200Y26900D02*
Y22900D01*
X113600D01*
G01X129019Y54924D02*
Y57424D01*
X130060D01*
X130394Y57299D01*
X130602Y57132D01*
X130685Y56799D01*
X130602Y56466D01*
X130352Y56257D01*
X130060Y56132D01*
X129019D01*
G01X130060D02*
X130685Y54924D01*
G01X132952D02*
Y57424D01*
X132452Y56924D01*
G01Y54924D02*
X133452D01*
G01X135969D02*
X136052Y55466D01*
X136177Y55924D01*
X136344Y56341D01*
X136552Y56799D01*
X136885Y57424D01*
X135219D01*
G01X127700Y52000D02*
Y56000D01*
X120300D01*
G01X86282Y31425D02*
Y33925D01*
X87323D01*
X87657Y33800D01*
X87865Y33633D01*
X87948Y33300D01*
X87865Y32967D01*
X87615Y32758D01*
X87323Y32633D01*
X86282D01*
G01X87323D02*
X87948Y31425D01*
G01X90215D02*
Y33925D01*
X89715Y33425D01*
G01Y31425D02*
X90715D01*
G01X92607Y31717D02*
X92898Y31508D01*
X93232Y31425D01*
X93565Y31508D01*
X93857Y31758D01*
X94065Y32133D01*
X94148Y32508D01*
Y32967D01*
X94065Y33342D01*
X93857Y33675D01*
X93607Y33842D01*
X93315Y33925D01*
X92982Y33842D01*
X92732Y33675D01*
X92565Y33425D01*
X92482Y33092D01*
X92565Y32800D01*
X92773Y32508D01*
X93023Y32342D01*
X93315Y32300D01*
X93648Y32383D01*
X93898Y32592D01*
X94148Y32967D01*
G01X103001Y30537D02*
Y34537D01*
X95601D01*
G01X124119Y18324D02*
Y20824D01*
X125160D01*
X125494Y20699D01*
X125702Y20532D01*
X125785Y20199D01*
X125702Y19866D01*
X125452Y19657D01*
X125160Y19532D01*
X124119D01*
G01X125160D02*
X125785Y18324D01*
G01X127260Y20407D02*
X127510Y20657D01*
X127802Y20782D01*
X128135Y20824D01*
X128552Y20741D01*
X128844Y20532D01*
X128927Y20282D01*
X128885Y20032D01*
X128719Y19824D01*
X127885Y19407D01*
X127510Y19116D01*
X127260Y18699D01*
X127177Y18324D01*
X128927D01*
G01X131152Y20824D02*
X130819Y20741D01*
X130569Y20532D01*
X130402Y20282D01*
X130277Y19949D01*
X130235Y19574D01*
X130277Y19199D01*
X130402Y18866D01*
X130569Y18616D01*
X130819Y18407D01*
X131152Y18324D01*
X131485Y18407D01*
X131735Y18616D01*
X131902Y18866D01*
X132027Y19199D01*
X132069Y19574D01*
X132027Y19949D01*
X131902Y20282D01*
X131735Y20532D01*
X131485Y20741D01*
X131152Y20824D01*
G01X128000Y26000D02*
Y22000D01*
X135400D01*
G01X95101Y46648D02*
X92601D01*
Y47689D01*
X92726Y48023D01*
X92893Y48231D01*
X93226Y48314D01*
X93559Y48231D01*
X93768Y47981D01*
X93893Y47689D01*
Y46648D01*
G01Y47689D02*
X95101Y48314D01*
G01Y50498D02*
X94559Y50581D01*
X94101Y50706D01*
X93684Y50873D01*
X93226Y51081D01*
X92601Y51414D01*
Y49748D01*
G01X94809Y52973D02*
X95018Y53264D01*
X95101Y53598D01*
X95018Y53931D01*
X94768Y54223D01*
X94393Y54431D01*
X94018Y54514D01*
X93559D01*
X93184Y54431D01*
X92851Y54223D01*
X92684Y53973D01*
X92601Y53681D01*
X92684Y53348D01*
X92851Y53098D01*
X93101Y52931D01*
X93434Y52848D01*
X93726Y52931D01*
X94018Y53139D01*
X94184Y53389D01*
X94226Y53681D01*
X94143Y54014D01*
X93934Y54264D01*
X93559Y54514D01*
G01X96071Y46225D02*
X100071D01*
Y53625D01*
G01X118619Y14224D02*
Y16724D01*
X119660D01*
X119994Y16599D01*
X120202Y16432D01*
X120285Y16099D01*
X120202Y15766D01*
X119952Y15557D01*
X119660Y15432D01*
X118619D01*
G01X119660D02*
X120285Y14224D01*
G01X122552D02*
X122844Y14266D01*
X123177Y14391D01*
X123385Y14599D01*
X123469Y14891D01*
X123385Y15182D01*
X123135Y15432D01*
X122760Y15557D01*
X122344D01*
X122094Y15641D01*
X121885Y15849D01*
X121802Y16141D01*
X121927Y16432D01*
X122219Y16641D01*
X122552Y16724D01*
X122885Y16641D01*
X123177Y16432D01*
X123302Y16141D01*
X123219Y15849D01*
X123010Y15641D01*
X122760Y15557D01*
X122344D01*
X121969Y15432D01*
X121719Y15182D01*
X121635Y14891D01*
X121719Y14599D01*
X121927Y14391D01*
X122260Y14266D01*
X122552Y14224D01*
G01X125652Y16724D02*
X125319Y16641D01*
X125069Y16432D01*
X124902Y16182D01*
X124777Y15849D01*
X124735Y15474D01*
X124777Y15099D01*
X124902Y14766D01*
X125069Y14516D01*
X125319Y14307D01*
X125652Y14224D01*
X125985Y14307D01*
X126235Y14516D01*
X126402Y14766D01*
X126527Y15099D01*
X126569Y15474D01*
X126527Y15849D01*
X126402Y16182D01*
X126235Y16432D01*
X125985Y16641D01*
X125652Y16724D01*
G01X122000Y21500D02*
Y25500D01*
X114600D01*
G01X86300Y51017D02*
X83800D01*
Y52058D01*
X83925Y52392D01*
X84092Y52600D01*
X84425Y52683D01*
X84758Y52600D01*
X84967Y52350D01*
X85092Y52058D01*
Y51017D01*
G01Y52058D02*
X86300Y52683D01*
G01Y54950D02*
X83800D01*
X84300Y54450D01*
G01X86300D02*
Y55450D01*
G01X78500Y56600D02*
X74500D01*
Y49200D01*
G01X82567Y46050D02*
Y48550D01*
X83608D01*
X83942Y48425D01*
X84150Y48258D01*
X84233Y47925D01*
X84150Y47592D01*
X83900Y47383D01*
X83608Y47258D01*
X82567D01*
G01X83608D02*
X84233Y46050D01*
G01X85583Y46550D02*
X85833Y46258D01*
X86167Y46092D01*
X86542Y46050D01*
X86875Y46092D01*
X87208Y46300D01*
X87417Y46550D01*
X87458Y46800D01*
X87375Y47092D01*
X87083Y47300D01*
X86792Y47383D01*
X86417D01*
G01X86792D02*
X87042Y47508D01*
X87250Y47717D01*
X87333Y47967D01*
X87250Y48217D01*
X87042Y48425D01*
X86667Y48550D01*
X86292Y48508D01*
X85917Y48342D01*
G01X73700Y49000D02*
Y45000D01*
X81100D01*
G01X89900Y51117D02*
X87400D01*
Y52158D01*
X87525Y52492D01*
X87692Y52700D01*
X88025Y52783D01*
X88358Y52700D01*
X88567Y52450D01*
X88692Y52158D01*
Y51117D01*
G01Y52158D02*
X89900Y52783D01*
G01X87817Y54258D02*
X87567Y54508D01*
X87442Y54800D01*
X87400Y55133D01*
X87483Y55550D01*
X87692Y55842D01*
X87942Y55925D01*
X88192Y55883D01*
X88400Y55717D01*
X88817Y54883D01*
X89108Y54508D01*
X89525Y54258D01*
X89900Y54175D01*
Y55925D01*
G01X82600Y56600D02*
X78600D01*
Y49200D01*
G01X83036Y58896D02*
Y61396D01*
X84077D01*
X84411Y61271D01*
X84619Y61104D01*
X84702Y60771D01*
X84619Y60438D01*
X84369Y60229D01*
X84077Y60104D01*
X83036D01*
G01X84077D02*
X84702Y58896D01*
G01X86177Y59938D02*
X86469Y60229D01*
X86719Y60396D01*
X87052Y60479D01*
X87344Y60396D01*
X87552Y60229D01*
X87719Y59979D01*
X87761Y59688D01*
X87719Y59438D01*
X87552Y59188D01*
X87302Y58979D01*
X87011Y58896D01*
X86677Y58979D01*
X86386Y59229D01*
X86219Y59604D01*
X86177Y60021D01*
X86261Y60563D01*
X86386Y60854D01*
X86594Y61146D01*
X86886Y61354D01*
X87177Y61396D01*
X87469Y61313D01*
X87677Y61104D01*
G01X90069Y58896D02*
Y61396D01*
X89569Y60896D01*
G01Y58896D02*
X90569D01*
G01X82867Y72100D02*
Y74600D01*
X83908D01*
X84242Y74475D01*
X84450Y74308D01*
X84533Y73975D01*
X84450Y73642D01*
X84200Y73433D01*
X83908Y73308D01*
X82867D01*
G01X83908D02*
X84533Y72100D01*
G01X86008Y73142D02*
X86300Y73433D01*
X86550Y73600D01*
X86883Y73683D01*
X87175Y73600D01*
X87383Y73433D01*
X87550Y73183D01*
X87592Y72892D01*
X87550Y72642D01*
X87383Y72392D01*
X87133Y72183D01*
X86842Y72100D01*
X86508Y72183D01*
X86217Y72433D01*
X86050Y72808D01*
X86008Y73225D01*
X86092Y73767D01*
X86217Y74058D01*
X86425Y74350D01*
X86717Y74558D01*
X87008Y74600D01*
X87300Y74517D01*
X87508Y74308D01*
G01X88983Y72600D02*
X89233Y72308D01*
X89567Y72142D01*
X89942Y72100D01*
X90275Y72142D01*
X90608Y72350D01*
X90817Y72600D01*
X90858Y72850D01*
X90775Y73142D01*
X90483Y73350D01*
X90192Y73433D01*
X89817D01*
G01X90192D02*
X90442Y73558D01*
X90650Y73767D01*
X90733Y74017D01*
X90650Y74267D01*
X90442Y74475D01*
X90067Y74600D01*
X89692Y74558D01*
X89317Y74392D01*
G01X81200Y75500D02*
X77200D01*
Y68100D01*
G01X82867Y64200D02*
Y66700D01*
X83908D01*
X84242Y66575D01*
X84450Y66408D01*
X84533Y66075D01*
X84450Y65742D01*
X84200Y65533D01*
X83908Y65408D01*
X82867D01*
G01X83908D02*
X84533Y64200D01*
G01X86008Y65242D02*
X86300Y65533D01*
X86550Y65700D01*
X86883Y65783D01*
X87175Y65700D01*
X87383Y65533D01*
X87550Y65283D01*
X87592Y64992D01*
X87550Y64742D01*
X87383Y64492D01*
X87133Y64283D01*
X86842Y64200D01*
X86508Y64283D01*
X86217Y64533D01*
X86050Y64908D01*
X86008Y65325D01*
X86092Y65867D01*
X86217Y66158D01*
X86425Y66450D01*
X86717Y66658D01*
X87008Y66700D01*
X87300Y66617D01*
X87508Y66408D01*
G01X89108Y65242D02*
X89400Y65533D01*
X89650Y65700D01*
X89983Y65783D01*
X90275Y65700D01*
X90483Y65533D01*
X90650Y65283D01*
X90692Y64992D01*
X90650Y64742D01*
X90483Y64492D01*
X90233Y64283D01*
X89942Y64200D01*
X89608Y64283D01*
X89317Y64533D01*
X89150Y64908D01*
X89108Y65325D01*
X89192Y65867D01*
X89317Y66158D01*
X89525Y66450D01*
X89817Y66658D01*
X90108Y66700D01*
X90400Y66617D01*
X90608Y66408D01*
G01X81200Y68000D02*
X77200D01*
Y60600D01*
G01X91967Y41942D02*
X91717Y42067D01*
X91425Y42150D01*
X91092D01*
X90717Y42025D01*
X90425Y41817D01*
X90217Y41567D01*
X90050Y41150D01*
X90008Y40775D01*
X90092Y40400D01*
X90217Y40150D01*
X90467Y39900D01*
X90758Y39733D01*
X91050Y39650D01*
X91342D01*
X91633Y39733D01*
X91883Y39858D01*
X92092Y40025D01*
G01X93358Y41733D02*
X93608Y41983D01*
X93900Y42108D01*
X94233Y42150D01*
X94650Y42067D01*
X94942Y41858D01*
X95025Y41608D01*
X94983Y41358D01*
X94817Y41150D01*
X93983Y40733D01*
X93608Y40442D01*
X93358Y40025D01*
X93275Y39650D01*
X95025D01*
G01X96542Y39942D02*
X96833Y39733D01*
X97167Y39650D01*
X97500Y39733D01*
X97792Y39983D01*
X98000Y40358D01*
X98083Y40733D01*
Y41192D01*
X98000Y41567D01*
X97792Y41900D01*
X97542Y42067D01*
X97250Y42150D01*
X96917Y42067D01*
X96667Y41900D01*
X96500Y41650D01*
X96417Y41317D01*
X96500Y41025D01*
X96708Y40733D01*
X96958Y40567D01*
X97250Y40525D01*
X97583Y40608D01*
X97833Y40817D01*
X98083Y41192D01*
G01X135458Y38467D02*
X135333Y38217D01*
X135250Y37925D01*
Y37592D01*
X135375Y37217D01*
X135583Y36925D01*
X135833Y36717D01*
X136250Y36550D01*
X136625Y36508D01*
X137000Y36592D01*
X137250Y36717D01*
X137500Y36967D01*
X137667Y37258D01*
X137750Y37550D01*
Y37842D01*
X137667Y38133D01*
X137542Y38383D01*
X137375Y38592D01*
G01X137250Y39733D02*
X137542Y39983D01*
X137708Y40317D01*
X137750Y40692D01*
X137708Y41025D01*
X137500Y41358D01*
X137250Y41567D01*
X137000Y41608D01*
X136708Y41525D01*
X136500Y41233D01*
X136417Y40942D01*
Y40567D01*
G01Y40942D02*
X136292Y41192D01*
X136083Y41400D01*
X135833Y41483D01*
X135583Y41400D01*
X135375Y41192D01*
X135250Y40817D01*
X135292Y40442D01*
X135458Y40067D01*
G01X135250Y43750D02*
X135333Y43417D01*
X135542Y43167D01*
X135792Y43000D01*
X136125Y42875D01*
X136500Y42833D01*
X136875Y42875D01*
X137208Y43000D01*
X137458Y43167D01*
X137667Y43417D01*
X137750Y43750D01*
X137667Y44083D01*
X137458Y44333D01*
X137208Y44500D01*
X136875Y44625D01*
X136500Y44667D01*
X136125Y44625D01*
X135792Y44500D01*
X135542Y44333D01*
X135333Y44083D01*
X135250Y43750D01*
G01X89958Y22467D02*
X89833Y22217D01*
X89750Y21925D01*
Y21592D01*
X89875Y21217D01*
X90083Y20925D01*
X90333Y20717D01*
X90750Y20550D01*
X91125Y20508D01*
X91500Y20592D01*
X91750Y20717D01*
X92000Y20967D01*
X92167Y21258D01*
X92250Y21550D01*
Y21842D01*
X92167Y22133D01*
X92042Y22383D01*
X91875Y22592D01*
G01X91750Y23733D02*
X92042Y23983D01*
X92208Y24317D01*
X92250Y24692D01*
X92208Y25025D01*
X92000Y25358D01*
X91750Y25567D01*
X91500Y25608D01*
X91208Y25525D01*
X91000Y25233D01*
X90917Y24942D01*
Y24567D01*
G01Y24942D02*
X90792Y25192D01*
X90583Y25400D01*
X90333Y25483D01*
X90083Y25400D01*
X89875Y25192D01*
X89750Y24817D01*
X89792Y24442D01*
X89958Y24067D01*
G01X92250Y27750D02*
X89750D01*
X90250Y27250D01*
G01X92250D02*
Y28250D01*
G01X137767Y50842D02*
X137517Y50967D01*
X137225Y51050D01*
X136892D01*
X136517Y50925D01*
X136225Y50717D01*
X136017Y50467D01*
X135850Y50050D01*
X135808Y49675D01*
X135892Y49300D01*
X136017Y49050D01*
X136267Y48800D01*
X136558Y48633D01*
X136850Y48550D01*
X137142D01*
X137433Y48633D01*
X137683Y48758D01*
X137892Y48925D01*
G01X139033Y49050D02*
X139283Y48758D01*
X139617Y48592D01*
X139992Y48550D01*
X140325Y48592D01*
X140658Y48800D01*
X140867Y49050D01*
X140908Y49300D01*
X140825Y49592D01*
X140533Y49800D01*
X140242Y49883D01*
X139867D01*
G01X140242D02*
X140492Y50008D01*
X140700Y50217D01*
X140783Y50467D01*
X140700Y50717D01*
X140492Y50925D01*
X140117Y51050D01*
X139742Y51008D01*
X139367Y50842D01*
G01X142258Y50633D02*
X142508Y50883D01*
X142800Y51008D01*
X143133Y51050D01*
X143550Y50967D01*
X143842Y50758D01*
X143925Y50508D01*
X143883Y50258D01*
X143717Y50050D01*
X142883Y49633D01*
X142508Y49342D01*
X142258Y48925D01*
X142175Y48550D01*
X143925D01*
G01X100167Y57342D02*
X99917Y57467D01*
X99625Y57550D01*
X99292D01*
X98917Y57425D01*
X98625Y57217D01*
X98417Y56967D01*
X98250Y56550D01*
X98208Y56175D01*
X98292Y55800D01*
X98417Y55550D01*
X98667Y55300D01*
X98958Y55133D01*
X99250Y55050D01*
X99542D01*
X99833Y55133D01*
X100083Y55258D01*
X100292Y55425D01*
G01X101433Y55550D02*
X101683Y55258D01*
X102017Y55092D01*
X102392Y55050D01*
X102725Y55092D01*
X103058Y55300D01*
X103267Y55550D01*
X103308Y55800D01*
X103225Y56092D01*
X102933Y56300D01*
X102642Y56383D01*
X102267D01*
G01X102642D02*
X102892Y56508D01*
X103100Y56717D01*
X103183Y56967D01*
X103100Y57217D01*
X102892Y57425D01*
X102517Y57550D01*
X102142Y57508D01*
X101767Y57342D01*
G01X104533Y55550D02*
X104783Y55258D01*
X105117Y55092D01*
X105492Y55050D01*
X105825Y55092D01*
X106158Y55300D01*
X106367Y55550D01*
X106408Y55800D01*
X106325Y56092D01*
X106033Y56300D01*
X105742Y56383D01*
X105367D01*
G01X105742D02*
X105992Y56508D01*
X106200Y56717D01*
X106283Y56967D01*
X106200Y57217D01*
X105992Y57425D01*
X105617Y57550D01*
X105242Y57508D01*
X104867Y57342D01*
G01X115067Y20642D02*
X114817Y20767D01*
X114525Y20850D01*
X114192D01*
X113817Y20725D01*
X113525Y20517D01*
X113317Y20267D01*
X113150Y19850D01*
X113108Y19475D01*
X113192Y19100D01*
X113317Y18850D01*
X113567Y18600D01*
X113858Y18433D01*
X114150Y18350D01*
X114442D01*
X114733Y18433D01*
X114983Y18558D01*
X115192Y18725D01*
G01X116333Y18850D02*
X116583Y18558D01*
X116917Y18392D01*
X117292Y18350D01*
X117625Y18392D01*
X117958Y18600D01*
X118167Y18850D01*
X118208Y19100D01*
X118125Y19392D01*
X117833Y19600D01*
X117542Y19683D01*
X117167D01*
G01X117542D02*
X117792Y19808D01*
X118000Y20017D01*
X118083Y20267D01*
X118000Y20517D01*
X117792Y20725D01*
X117417Y20850D01*
X117042Y20808D01*
X116667Y20642D01*
G01X120850Y18350D02*
Y20850D01*
X119308Y19058D01*
X121392D01*
G01X90000Y79867D02*
X87500D01*
Y80908D01*
X87625Y81242D01*
X87792Y81450D01*
X88125Y81533D01*
X88458Y81450D01*
X88667Y81200D01*
X88792Y80908D01*
Y79867D01*
G01Y80908D02*
X90000Y81533D01*
G01X88958Y83008D02*
X88667Y83300D01*
X88500Y83550D01*
X88417Y83883D01*
X88500Y84175D01*
X88667Y84383D01*
X88917Y84550D01*
X89208Y84592D01*
X89458Y84550D01*
X89708Y84383D01*
X89917Y84133D01*
X90000Y83842D01*
X89917Y83508D01*
X89667Y83217D01*
X89292Y83050D01*
X88875Y83008D01*
X88333Y83092D01*
X88042Y83217D01*
X87750Y83425D01*
X87542Y83717D01*
X87500Y84008D01*
X87583Y84300D01*
X87792Y84508D01*
G01X90000Y87400D02*
X87500D01*
X89292Y85858D01*
Y87942D01*
G01X81604Y85769D02*
X77604D01*
Y78369D01*
G01X86000Y79867D02*
X83500D01*
Y80908D01*
X83625Y81242D01*
X83792Y81450D01*
X84125Y81533D01*
X84458Y81450D01*
X84667Y81200D01*
X84792Y80908D01*
Y79867D01*
G01Y80908D02*
X86000Y81533D01*
G01X84958Y83008D02*
X84667Y83300D01*
X84500Y83550D01*
X84417Y83883D01*
X84500Y84175D01*
X84667Y84383D01*
X84917Y84550D01*
X85208Y84592D01*
X85458Y84550D01*
X85708Y84383D01*
X85917Y84133D01*
X86000Y83842D01*
X85917Y83508D01*
X85667Y83217D01*
X85292Y83050D01*
X84875Y83008D01*
X84333Y83092D01*
X84042Y83217D01*
X83750Y83425D01*
X83542Y83717D01*
X83500Y84008D01*
X83583Y84300D01*
X83792Y84508D01*
G01X86000Y86817D02*
X85458Y86900D01*
X85000Y87025D01*
X84583Y87192D01*
X84125Y87400D01*
X83500Y87733D01*
Y86067D01*
G01X73604Y78369D02*
X77604D01*
Y85769D01*
G01X137875Y87833D02*
X138208Y87625D01*
X138583Y87500D01*
X138917D01*
X139250Y87625D01*
X139500Y87833D01*
X139625Y88125D01*
X139542Y88417D01*
X139333Y88667D01*
X138958Y88833D01*
X138458Y88917D01*
X138167Y89083D01*
X138042Y89375D01*
X138125Y89667D01*
X138333Y89875D01*
X138625Y90000D01*
X138917D01*
X139208Y89917D01*
X139458Y89708D01*
G01X142767Y89792D02*
X142517Y89917D01*
X142225Y90000D01*
X141892D01*
X141517Y89875D01*
X141225Y89667D01*
X141017Y89417D01*
X140850Y89000D01*
X140808Y88625D01*
X140892Y88250D01*
X141017Y88000D01*
X141267Y87750D01*
X141558Y87583D01*
X141850Y87500D01*
X142142D01*
X142433Y87583D01*
X142683Y87708D01*
X142892Y87875D01*
G01X143700Y90000D02*
X144283Y87500D01*
X144950Y90000D01*
X145617Y87500D01*
X146200Y90000D01*
G01X148050Y87500D02*
Y90000D01*
X147550Y89500D01*
G01Y87500D02*
X148550D01*
G01X156128Y15774D02*
X155878Y15899D01*
X155586Y15982D01*
X155253D01*
X154878Y15857D01*
X154586Y15649D01*
X154378Y15399D01*
X154211Y14982D01*
X154169Y14607D01*
X154253Y14232D01*
X154378Y13982D01*
X154628Y13732D01*
X154919Y13565D01*
X155211Y13482D01*
X155503D01*
X155794Y13565D01*
X156044Y13690D01*
X156253Y13857D01*
G01X157353Y13482D02*
Y15982D01*
X159269Y13482D01*
Y15982D01*
G01X161411Y13482D02*
Y15982D01*
X160911Y15482D01*
G01Y13482D02*
X161911D01*
G01X225000Y58850D02*
X204000D01*
Y90500D01*
X215000D01*
Y58850D01*
G01X206350D02*
X209500Y62000D01*
X212650Y58850D01*
G01X162083Y30600D02*
Y28808D01*
X162250Y28433D01*
X162583Y28183D01*
X163000Y28100D01*
X163417Y28183D01*
X163750Y28433D01*
X163917Y28808D01*
Y30600D01*
G01X166100Y28100D02*
Y30600D01*
X165600Y30100D01*
G01Y28100D02*
X166600D01*
G01X168283Y28600D02*
X168533Y28308D01*
X168867Y28142D01*
X169242Y28100D01*
X169575Y28142D01*
X169908Y28350D01*
X170117Y28600D01*
X170158Y28850D01*
X170075Y29142D01*
X169783Y29350D01*
X169492Y29433D01*
X169117D01*
G01X169492D02*
X169742Y29558D01*
X169950Y29767D01*
X170033Y30017D01*
X169950Y30267D01*
X169742Y30475D01*
X169367Y30600D01*
X168992Y30558D01*
X168617Y30392D01*
G01X173402Y33082D02*
X160002D01*
G01X173402Y43082D02*
Y33082D01*
G01X160002Y43082D02*
X173402D01*
G01X160002Y33082D02*
Y43082D01*
G01X150483Y58500D02*
Y56708D01*
X150650Y56333D01*
X150983Y56083D01*
X151400Y56000D01*
X151817Y56083D01*
X152150Y56333D01*
X152317Y56708D01*
Y58500D01*
G01X154500Y56000D02*
Y58500D01*
X154000Y58000D01*
G01Y56000D02*
X155000D01*
G01X158100D02*
Y58500D01*
X156558Y56708D01*
X158642D01*
G01X160800Y62000D02*
X174200D01*
G01X160800Y52000D02*
Y62000D01*
G01X174200Y52000D02*
X160800D01*
G01X174200Y62000D02*
Y52000D01*
G01X197933Y19000D02*
Y17208D01*
X198100Y16833D01*
X198433Y16583D01*
X198850Y16500D01*
X199267Y16583D01*
X199600Y16833D01*
X199767Y17208D01*
Y19000D01*
G01X201033Y17000D02*
X201283Y16708D01*
X201617Y16542D01*
X201992Y16500D01*
X202325Y16542D01*
X202658Y16750D01*
X202867Y17000D01*
X202908Y17250D01*
X202825Y17542D01*
X202533Y17750D01*
X202242Y17833D01*
X201867D01*
G01X202242D02*
X202492Y17958D01*
X202700Y18167D01*
X202783Y18417D01*
X202700Y18667D01*
X202492Y18875D01*
X202117Y19000D01*
X201742Y18958D01*
X201367Y18792D01*
G01X203000Y30600D02*
X195000D01*
Y43000D01*
X203000D01*
Y30600D01*
G01X199000Y32300D02*
X197500Y30800D01*
G01X199000Y32300D02*
X200500Y30800D01*
G01X217500Y51200D02*
X221500D01*
Y58600D01*
G01X189600Y47767D02*
X187100D01*
Y48808D01*
X187225Y49142D01*
X187392Y49350D01*
X187725Y49433D01*
X188058Y49350D01*
X188267Y49100D01*
X188392Y48808D01*
Y47767D01*
G01Y48808D02*
X189600Y49433D01*
G01X188558Y50908D02*
X188267Y51200D01*
X188100Y51450D01*
X188017Y51783D01*
X188100Y52075D01*
X188267Y52283D01*
X188517Y52450D01*
X188808Y52492D01*
X189058Y52450D01*
X189308Y52283D01*
X189517Y52033D01*
X189600Y51742D01*
X189517Y51408D01*
X189267Y51117D01*
X188892Y50950D01*
X188475Y50908D01*
X187933Y50992D01*
X187642Y51117D01*
X187350Y51325D01*
X187142Y51617D01*
X187100Y51908D01*
X187183Y52200D01*
X187392Y52408D01*
G01X189308Y54092D02*
X189517Y54383D01*
X189600Y54717D01*
X189517Y55050D01*
X189267Y55342D01*
X188892Y55550D01*
X188517Y55633D01*
X188058D01*
X187683Y55550D01*
X187350Y55342D01*
X187183Y55092D01*
X187100Y54800D01*
X187183Y54467D01*
X187350Y54217D01*
X187600Y54050D01*
X187933Y53967D01*
X188225Y54050D01*
X188517Y54258D01*
X188683Y54508D01*
X188725Y54800D01*
X188642Y55133D01*
X188433Y55383D01*
X188058Y55633D01*
G01X190250Y64496D02*
X186250D01*
Y57096D01*
G01X190500Y64800D02*
X194500D01*
Y72200D01*
G01X224500Y44200D02*
X220500D01*
Y36800D01*
G01X216300Y33800D02*
X220300D01*
Y41200D01*
G01X221378Y31305D02*
X217378D01*
Y23905D01*
G01X223934Y12667D02*
X221434D01*
Y13708D01*
X221559Y14042D01*
X221726Y14250D01*
X222059Y14333D01*
X222392Y14250D01*
X222601Y14000D01*
X222726Y13708D01*
Y12667D01*
G01Y13708D02*
X223934Y14333D01*
G01Y16517D02*
X223392Y16600D01*
X222934Y16725D01*
X222517Y16892D01*
X222059Y17100D01*
X221434Y17433D01*
Y15767D01*
G01X223934Y20200D02*
X221434D01*
X223226Y18658D01*
Y20742D01*
G01X213378Y23905D02*
X217378D01*
Y31305D01*
G01X177467Y64900D02*
Y67400D01*
X178508D01*
X178842Y67275D01*
X179050Y67108D01*
X179133Y66775D01*
X179050Y66442D01*
X178800Y66233D01*
X178508Y66108D01*
X177467D01*
G01X178508D02*
X179133Y64900D01*
G01X180483Y65275D02*
X180733Y65067D01*
X181025Y64942D01*
X181400Y64900D01*
X181775Y64983D01*
X182067Y65150D01*
X182275Y65442D01*
X182317Y65775D01*
X182233Y66108D01*
X182025Y66317D01*
X181733Y66483D01*
X181442Y66525D01*
X181150Y66483D01*
X180775Y66317D01*
X180900Y67400D01*
X182025D01*
G01X184417Y64900D02*
X184500Y65442D01*
X184625Y65900D01*
X184792Y66317D01*
X185000Y66775D01*
X185333Y67400D01*
X183667D01*
G01X190200Y68200D02*
Y72200D01*
X182800D01*
G01X167367Y64400D02*
Y66900D01*
X168408D01*
X168742Y66775D01*
X168950Y66608D01*
X169033Y66275D01*
X168950Y65942D01*
X168700Y65733D01*
X168408Y65608D01*
X167367D01*
G01X168408D02*
X169033Y64400D01*
G01X170383Y64775D02*
X170633Y64567D01*
X170925Y64442D01*
X171300Y64400D01*
X171675Y64483D01*
X171967Y64650D01*
X172175Y64942D01*
X172217Y65275D01*
X172133Y65608D01*
X171925Y65817D01*
X171633Y65983D01*
X171342Y66025D01*
X171050Y65983D01*
X170675Y65817D01*
X170800Y66900D01*
X171925D01*
G01X174400Y64400D02*
X174692Y64442D01*
X175025Y64567D01*
X175233Y64775D01*
X175317Y65067D01*
X175233Y65358D01*
X174983Y65608D01*
X174608Y65733D01*
X174192D01*
X173942Y65817D01*
X173733Y66025D01*
X173650Y66317D01*
X173775Y66608D01*
X174067Y66817D01*
X174400Y66900D01*
X174733Y66817D01*
X175025Y66608D01*
X175150Y66317D01*
X175067Y66025D01*
X174858Y65817D01*
X174608Y65733D01*
X174192D01*
X173817Y65608D01*
X173567Y65358D01*
X173483Y65067D01*
X173567Y64775D01*
X173775Y64567D01*
X174108Y64442D01*
X174400Y64400D01*
G01X175300Y72200D02*
Y68200D01*
X182700D01*
G01X177467Y47500D02*
Y50000D01*
X178508D01*
X178842Y49875D01*
X179050Y49708D01*
X179133Y49375D01*
X179050Y49042D01*
X178800Y48833D01*
X178508Y48708D01*
X177467D01*
G01X178508D02*
X179133Y47500D01*
G01X180608Y48542D02*
X180900Y48833D01*
X181150Y49000D01*
X181483Y49083D01*
X181775Y49000D01*
X181983Y48833D01*
X182150Y48583D01*
X182192Y48292D01*
X182150Y48042D01*
X181983Y47792D01*
X181733Y47583D01*
X181442Y47500D01*
X181108Y47583D01*
X180817Y47833D01*
X180650Y48208D01*
X180608Y48625D01*
X180692Y49167D01*
X180817Y49458D01*
X181025Y49750D01*
X181317Y49958D01*
X181608Y50000D01*
X181900Y49917D01*
X182108Y49708D01*
G01X184500Y50000D02*
X184167Y49917D01*
X183917Y49708D01*
X183750Y49458D01*
X183625Y49125D01*
X183583Y48750D01*
X183625Y48375D01*
X183750Y48042D01*
X183917Y47792D01*
X184167Y47583D01*
X184500Y47500D01*
X184833Y47583D01*
X185083Y47792D01*
X185250Y48042D01*
X185375Y48375D01*
X185417Y48750D01*
X185375Y49125D01*
X185250Y49458D01*
X185083Y49708D01*
X184833Y49917D01*
X184500Y50000D01*
G01X168900Y50800D02*
Y46800D01*
X176300D01*
G01X204900Y20967D02*
X202400D01*
Y22008D01*
X202525Y22342D01*
X202692Y22550D01*
X203025Y22633D01*
X203358Y22550D01*
X203567Y22300D01*
X203692Y22008D01*
Y20967D01*
G01Y22008D02*
X204900Y22633D01*
G01Y24900D02*
X202400D01*
X202900Y24400D01*
G01X204900D02*
Y25400D01*
G01Y28500D02*
X202400D01*
X204192Y26958D01*
Y29042D01*
G01X207500Y54200D02*
X203500D01*
Y46800D01*
G01X217300Y58600D02*
X213300D01*
Y51200D01*
G01X208800Y23917D02*
X206300D01*
Y24958D01*
X206425Y25292D01*
X206592Y25500D01*
X206925Y25583D01*
X207258Y25500D01*
X207467Y25250D01*
X207592Y24958D01*
Y23917D01*
G01Y24958D02*
X208800Y25583D01*
G01Y27850D02*
X208758Y28142D01*
X208633Y28475D01*
X208425Y28683D01*
X208133Y28767D01*
X207842Y28683D01*
X207592Y28433D01*
X207467Y28058D01*
Y27642D01*
X207383Y27392D01*
X207175Y27183D01*
X206883Y27100D01*
X206592Y27225D01*
X206383Y27517D01*
X206300Y27850D01*
X206383Y28183D01*
X206592Y28475D01*
X206883Y28600D01*
X207175Y28517D01*
X207383Y28308D01*
X207467Y28058D01*
Y27642D01*
X207592Y27267D01*
X207842Y27017D01*
X208133Y26933D01*
X208425Y27017D01*
X208633Y27225D01*
X208758Y27558D01*
X208800Y27850D01*
G01X207522Y46812D02*
X211522D01*
Y54212D01*
G01X200900Y20967D02*
X198400D01*
Y22008D01*
X198525Y22342D01*
X198692Y22550D01*
X199025Y22633D01*
X199358Y22550D01*
X199567Y22300D01*
X199692Y22008D01*
Y20967D01*
G01Y22008D02*
X200900Y22633D01*
G01Y24900D02*
X198400D01*
X198900Y24400D01*
G01X200900D02*
Y25400D01*
G01X198817Y27208D02*
X198567Y27458D01*
X198442Y27750D01*
X198400Y28083D01*
X198483Y28500D01*
X198692Y28792D01*
X198942Y28875D01*
X199192Y28833D01*
X199400Y28667D01*
X199817Y27833D01*
X200108Y27458D01*
X200525Y27208D01*
X200900Y27125D01*
Y28875D01*
G01X203500Y54200D02*
X199500D01*
Y46800D01*
G01X156383Y67973D02*
Y70473D01*
X157424D01*
X157758Y70348D01*
X157966Y70181D01*
X158049Y69848D01*
X157966Y69515D01*
X157716Y69306D01*
X157424Y69181D01*
X156383D01*
G01X157424D02*
X158049Y67973D01*
G01X160316D02*
Y70473D01*
X159816Y69973D01*
G01Y67973D02*
X160816D01*
G01X163416D02*
Y70473D01*
X162916Y69973D01*
G01Y67973D02*
X163916D01*
G01X174887Y68136D02*
Y72136D01*
X167487D01*
G01X215282Y51139D02*
Y47139D01*
X222682D01*
G01X175208Y25817D02*
X175083Y25567D01*
X175000Y25275D01*
Y24942D01*
X175125Y24567D01*
X175333Y24275D01*
X175583Y24067D01*
X176000Y23900D01*
X176375Y23858D01*
X176750Y23942D01*
X177000Y24067D01*
X177250Y24317D01*
X177417Y24608D01*
X177500Y24900D01*
Y25192D01*
X177417Y25483D01*
X177292Y25733D01*
X177125Y25942D01*
G01X175417Y27208D02*
X175167Y27458D01*
X175042Y27750D01*
X175000Y28083D01*
X175083Y28500D01*
X175292Y28792D01*
X175542Y28875D01*
X175792Y28833D01*
X176000Y28667D01*
X176417Y27833D01*
X176708Y27458D01*
X177125Y27208D01*
X177500Y27125D01*
Y28875D01*
G01X177125Y30183D02*
X177333Y30433D01*
X177458Y30725D01*
X177500Y31100D01*
X177417Y31475D01*
X177250Y31767D01*
X176958Y31975D01*
X176625Y32017D01*
X176292Y31933D01*
X176083Y31725D01*
X175917Y31433D01*
X175875Y31142D01*
X175917Y30850D01*
X176083Y30475D01*
X175000Y30600D01*
Y31725D01*
G01X152017Y48992D02*
X151767Y49117D01*
X151475Y49200D01*
X151142D01*
X150767Y49075D01*
X150475Y48867D01*
X150267Y48617D01*
X150100Y48200D01*
X150058Y47825D01*
X150142Y47450D01*
X150267Y47200D01*
X150517Y46950D01*
X150808Y46783D01*
X151100Y46700D01*
X151392D01*
X151683Y46783D01*
X151933Y46908D01*
X152142Y47075D01*
G01X153408Y48783D02*
X153658Y49033D01*
X153950Y49158D01*
X154283Y49200D01*
X154700Y49117D01*
X154992Y48908D01*
X155075Y48658D01*
X155033Y48408D01*
X154867Y48200D01*
X154033Y47783D01*
X153658Y47492D01*
X153408Y47075D01*
X153325Y46700D01*
X155075D01*
G01X156508Y47742D02*
X156800Y48033D01*
X157050Y48200D01*
X157383Y48283D01*
X157675Y48200D01*
X157883Y48033D01*
X158050Y47783D01*
X158092Y47492D01*
X158050Y47242D01*
X157883Y46992D01*
X157633Y46783D01*
X157342Y46700D01*
X157008Y46783D01*
X156717Y47033D01*
X156550Y47408D01*
X156508Y47825D01*
X156592Y48367D01*
X156717Y48658D01*
X156925Y48950D01*
X157217Y49158D01*
X157508Y49200D01*
X157800Y49117D01*
X158008Y48908D01*
G01X182308Y33267D02*
X182183Y33017D01*
X182100Y32725D01*
Y32392D01*
X182225Y32017D01*
X182433Y31725D01*
X182683Y31517D01*
X183100Y31350D01*
X183475Y31308D01*
X183850Y31392D01*
X184100Y31517D01*
X184350Y31767D01*
X184517Y32058D01*
X184600Y32350D01*
Y32642D01*
X184517Y32933D01*
X184392Y33183D01*
X184225Y33392D01*
G01X183558Y34658D02*
X183267Y34950D01*
X183100Y35200D01*
X183017Y35533D01*
X183100Y35825D01*
X183267Y36033D01*
X183517Y36200D01*
X183808Y36242D01*
X184058Y36200D01*
X184308Y36033D01*
X184517Y35783D01*
X184600Y35492D01*
X184517Y35158D01*
X184267Y34867D01*
X183892Y34700D01*
X183475Y34658D01*
X182933Y34742D01*
X182642Y34867D01*
X182350Y35075D01*
X182142Y35367D01*
X182100Y35658D01*
X182183Y35950D01*
X182392Y36158D01*
G01X192408Y50017D02*
X192283Y49767D01*
X192200Y49475D01*
Y49142D01*
X192325Y48767D01*
X192533Y48475D01*
X192783Y48267D01*
X193200Y48100D01*
X193575Y48058D01*
X193950Y48142D01*
X194200Y48267D01*
X194450Y48517D01*
X194617Y48808D01*
X194700Y49100D01*
Y49392D01*
X194617Y49683D01*
X194492Y49933D01*
X194325Y50142D01*
G01X194700Y52200D02*
X192200D01*
X192700Y51700D01*
G01X194700D02*
Y52700D01*
G01X192200Y55300D02*
X192283Y54967D01*
X192492Y54717D01*
X192742Y54550D01*
X193075Y54425D01*
X193450Y54383D01*
X193825Y54425D01*
X194158Y54550D01*
X194408Y54717D01*
X194617Y54967D01*
X194700Y55300D01*
X194617Y55633D01*
X194408Y55883D01*
X194158Y56050D01*
X193825Y56175D01*
X193450Y56217D01*
X193075Y56175D01*
X192742Y56050D01*
X192492Y55883D01*
X192283Y55633D01*
X192200Y55300D01*
G01X200033Y95400D02*
Y93608D01*
X200200Y93233D01*
X200533Y92983D01*
X200950Y92900D01*
X201367Y92983D01*
X201700Y93233D01*
X201867Y93608D01*
Y95400D01*
G01X204550Y92900D02*
Y95400D01*
X203008Y93608D01*
X205092D01*
G01X206283Y98500D02*
Y96708D01*
X206450Y96333D01*
X206783Y96083D01*
X207200Y96000D01*
X207617Y96083D01*
X207950Y96333D01*
X208117Y96708D01*
Y98500D01*
G01X210300Y96000D02*
Y98500D01*
X209800Y98000D01*
G01Y96000D02*
X210800D01*
G01X212608Y97042D02*
X212900Y97333D01*
X213150Y97500D01*
X213483Y97583D01*
X213775Y97500D01*
X213983Y97333D01*
X214150Y97083D01*
X214192Y96792D01*
X214150Y96542D01*
X213983Y96292D01*
X213733Y96083D01*
X213442Y96000D01*
X213108Y96083D01*
X212817Y96333D01*
X212650Y96708D01*
X212608Y97125D01*
X212692Y97667D01*
X212817Y97958D01*
X213025Y98250D01*
X213317Y98458D01*
X213608Y98500D01*
X213900Y98417D01*
X214108Y98208D01*
G01X213000Y100500D02*
X199600D01*
G01X213000Y110500D02*
Y100500D01*
G01X199600Y110500D02*
X213000D01*
G01X199600Y100500D02*
Y110500D01*
G01X172983Y93400D02*
Y91608D01*
X173150Y91233D01*
X173483Y90983D01*
X173900Y90900D01*
X174317Y90983D01*
X174650Y91233D01*
X174817Y91608D01*
Y93400D01*
G01X177000Y90900D02*
Y93400D01*
X176500Y92900D01*
G01Y90900D02*
X177500D01*
G01X179308Y92983D02*
X179558Y93233D01*
X179850Y93358D01*
X180183Y93400D01*
X180600Y93317D01*
X180892Y93108D01*
X180975Y92858D01*
X180933Y92608D01*
X180767Y92400D01*
X179933Y91983D01*
X179558Y91692D01*
X179308Y91275D01*
X179225Y90900D01*
X180975D01*
G01X178700Y75300D02*
Y85500D01*
G01X183300Y75300D02*
X178700D01*
G01X183300Y86200D02*
Y75300D01*
G01Y86200D02*
X172000D01*
G01X181000Y85000D02*
X182200Y86200D01*
G01X181000Y85000D02*
X179800Y86200D01*
G01X171847Y116366D02*
Y118866D01*
X172681D01*
X173014Y118741D01*
X173264Y118574D01*
X173472Y118324D01*
X173639Y118033D01*
X173681Y117616D01*
X173639Y117199D01*
X173472Y116908D01*
X173264Y116658D01*
X173014Y116491D01*
X172681Y116366D01*
X171847D01*
G01X175864D02*
Y118866D01*
X175364Y118366D01*
G01Y116366D02*
X176364D01*
G01X178964Y118866D02*
X178631Y118783D01*
X178381Y118574D01*
X178214Y118324D01*
X178089Y117991D01*
X178047Y117616D01*
X178089Y117241D01*
X178214Y116908D01*
X178381Y116658D01*
X178631Y116449D01*
X178964Y116366D01*
X179297Y116449D01*
X179547Y116658D01*
X179714Y116908D01*
X179839Y117241D01*
X179881Y117616D01*
X179839Y117991D01*
X179714Y118324D01*
X179547Y118574D01*
X179297Y118783D01*
X178964Y118866D01*
G01X194900Y117800D02*
Y113600D01*
G01X183200Y117800D02*
X194900D01*
G01X183200Y113600D02*
Y117800D01*
G01X194900Y113600D02*
X183200D01*
G01X222788Y118400D02*
Y116608D01*
X222955Y116233D01*
X223288Y115983D01*
X223705Y115900D01*
X224122Y115983D01*
X224455Y116233D01*
X224622Y116608D01*
Y118400D01*
G01X226013Y116942D02*
X226305Y117233D01*
X226555Y117400D01*
X226888Y117483D01*
X227180Y117400D01*
X227388Y117233D01*
X227555Y116983D01*
X227597Y116692D01*
X227555Y116442D01*
X227388Y116192D01*
X227138Y115983D01*
X226847Y115900D01*
X226513Y115983D01*
X226222Y116233D01*
X226055Y116608D01*
X226013Y117025D01*
X226097Y117567D01*
X226222Y117858D01*
X226430Y118150D01*
X226722Y118358D01*
X227013Y118400D01*
X227305Y118317D01*
X227513Y118108D01*
G01X206755Y112850D02*
Y113550D01*
X205755Y114550D01*
X205055D01*
G01X210755Y112850D02*
Y113550D01*
X211755Y114550D01*
X212455D01*
G01Y120250D02*
X211755D01*
X210755Y121250D01*
Y121950D01*
G01X177839Y103195D02*
X175339D01*
Y104236D01*
X175464Y104570D01*
X175631Y104778D01*
X175964Y104861D01*
X176297Y104778D01*
X176506Y104528D01*
X176631Y104236D01*
Y103195D01*
G01Y104236D02*
X177839Y104861D01*
G01Y107045D02*
X177297Y107128D01*
X176839Y107253D01*
X176422Y107420D01*
X175964Y107628D01*
X175339Y107961D01*
Y106295D01*
G01X176797Y109436D02*
X176506Y109728D01*
X176339Y109978D01*
X176256Y110311D01*
X176339Y110603D01*
X176506Y110811D01*
X176756Y110978D01*
X177047Y111020D01*
X177297Y110978D01*
X177547Y110811D01*
X177756Y110561D01*
X177839Y110270D01*
X177756Y109936D01*
X177506Y109645D01*
X177131Y109478D01*
X176714Y109436D01*
X176172Y109520D01*
X175881Y109645D01*
X175589Y109853D01*
X175381Y110145D01*
X175339Y110436D01*
X175422Y110728D01*
X175631Y110936D01*
G01X178800Y102900D02*
X182800D01*
Y110300D01*
G01X185967Y93200D02*
Y95700D01*
X187008D01*
X187342Y95575D01*
X187550Y95408D01*
X187633Y95075D01*
X187550Y94742D01*
X187300Y94533D01*
X187008Y94408D01*
X185967D01*
G01X187008D02*
X187633Y93200D01*
G01X189817D02*
X189900Y93742D01*
X190025Y94200D01*
X190192Y94617D01*
X190400Y95075D01*
X190733Y95700D01*
X189067D01*
G01X193000D02*
X192667Y95617D01*
X192417Y95408D01*
X192250Y95158D01*
X192125Y94825D01*
X192083Y94450D01*
X192125Y94075D01*
X192250Y93742D01*
X192417Y93492D01*
X192667Y93283D01*
X193000Y93200D01*
X193333Y93283D01*
X193583Y93492D01*
X193750Y93742D01*
X193875Y94075D01*
X193917Y94450D01*
X193875Y94825D01*
X193750Y95158D01*
X193583Y95408D01*
X193333Y95617D01*
X193000Y95700D01*
G01X185767Y100900D02*
Y103400D01*
X186808D01*
X187142Y103275D01*
X187350Y103108D01*
X187433Y102775D01*
X187350Y102442D01*
X187100Y102233D01*
X186808Y102108D01*
X185767D01*
G01X186808D02*
X187433Y100900D01*
G01X189617D02*
X189700Y101442D01*
X189825Y101900D01*
X189992Y102317D01*
X190200Y102775D01*
X190533Y103400D01*
X188867D01*
G01X192800Y100900D02*
X193092Y100942D01*
X193425Y101067D01*
X193633Y101275D01*
X193717Y101567D01*
X193633Y101858D01*
X193383Y102108D01*
X193008Y102233D01*
X192592D01*
X192342Y102317D01*
X192133Y102525D01*
X192050Y102817D01*
X192175Y103108D01*
X192467Y103317D01*
X192800Y103400D01*
X193133Y103317D01*
X193425Y103108D01*
X193550Y102817D01*
X193467Y102525D01*
X193258Y102317D01*
X193008Y102233D01*
X192592D01*
X192217Y102108D01*
X191967Y101858D01*
X191883Y101567D01*
X191967Y101275D01*
X192175Y101067D01*
X192508Y100942D01*
X192800Y100900D01*
G01X186800Y92000D02*
Y88000D01*
X194200D01*
G01X225200Y123567D02*
X222700D01*
Y124608D01*
X222825Y124942D01*
X222992Y125150D01*
X223325Y125233D01*
X223658Y125150D01*
X223867Y124900D01*
X223992Y124608D01*
Y123567D01*
G01Y124608D02*
X225200Y125233D01*
G01X224825Y126583D02*
X225033Y126833D01*
X225158Y127125D01*
X225200Y127500D01*
X225117Y127875D01*
X224950Y128167D01*
X224658Y128375D01*
X224325Y128417D01*
X223992Y128333D01*
X223783Y128125D01*
X223617Y127833D01*
X223575Y127542D01*
X223617Y127250D01*
X223783Y126875D01*
X222700Y127000D01*
Y128125D01*
G01X224700Y129683D02*
X224992Y129933D01*
X225158Y130267D01*
X225200Y130642D01*
X225158Y130975D01*
X224950Y131308D01*
X224700Y131517D01*
X224450Y131558D01*
X224158Y131475D01*
X223950Y131183D01*
X223867Y130892D01*
Y130517D01*
G01Y130892D02*
X223742Y131142D01*
X223533Y131350D01*
X223283Y131433D01*
X223033Y131350D01*
X222825Y131142D01*
X222700Y130767D01*
X222742Y130392D01*
X222908Y130017D01*
G01X220832Y130259D02*
X216832D01*
Y122859D01*
G01X220267Y109900D02*
Y112400D01*
X221308D01*
X221642Y112275D01*
X221850Y112108D01*
X221933Y111775D01*
X221850Y111442D01*
X221600Y111233D01*
X221308Y111108D01*
X220267D01*
G01X221308D02*
X221933Y109900D01*
G01X223283Y110275D02*
X223533Y110067D01*
X223825Y109942D01*
X224200Y109900D01*
X224575Y109983D01*
X224867Y110150D01*
X225075Y110442D01*
X225117Y110775D01*
X225033Y111108D01*
X224825Y111317D01*
X224533Y111483D01*
X224242Y111525D01*
X223950Y111483D01*
X223575Y111317D01*
X223700Y112400D01*
X224825D01*
G01X227800Y109900D02*
Y112400D01*
X226258Y110608D01*
X228342D01*
G01X212900Y121000D02*
Y117000D01*
X220300D01*
G01X189000Y108156D02*
Y110656D01*
X190041D01*
X190375Y110531D01*
X190583Y110364D01*
X190666Y110031D01*
X190583Y109698D01*
X190333Y109489D01*
X190041Y109364D01*
X189000D01*
G01X190041D02*
X190666Y108156D01*
G01X192016Y108531D02*
X192266Y108323D01*
X192558Y108198D01*
X192933Y108156D01*
X193308Y108239D01*
X193600Y108406D01*
X193808Y108698D01*
X193850Y109031D01*
X193766Y109364D01*
X193558Y109573D01*
X193266Y109739D01*
X192975Y109781D01*
X192683Y109739D01*
X192308Y109573D01*
X192433Y110656D01*
X193558D01*
G01X196033Y108156D02*
Y110656D01*
X195533Y110156D01*
G01Y108156D02*
X196533D01*
G01X203920Y111600D02*
Y115600D01*
X196520D01*
G01X180743Y120378D02*
Y122878D01*
X181784D01*
X182118Y122753D01*
X182326Y122586D01*
X182409Y122253D01*
X182326Y121920D01*
X182076Y121711D01*
X181784Y121586D01*
X180743D01*
G01X181784D02*
X182409Y120378D01*
G01X183759Y120753D02*
X184009Y120545D01*
X184301Y120420D01*
X184676Y120378D01*
X185051Y120461D01*
X185343Y120628D01*
X185551Y120920D01*
X185593Y121253D01*
X185509Y121586D01*
X185301Y121795D01*
X185009Y121961D01*
X184718Y122003D01*
X184426Y121961D01*
X184051Y121795D01*
X184176Y122878D01*
X185301D01*
G01X186984Y122461D02*
X187234Y122711D01*
X187526Y122836D01*
X187859Y122878D01*
X188276Y122795D01*
X188568Y122586D01*
X188651Y122336D01*
X188609Y122086D01*
X188443Y121878D01*
X187609Y121461D01*
X187234Y121170D01*
X186984Y120753D01*
X186901Y120378D01*
X188651D01*
G01X198171Y119500D02*
Y123500D01*
X190771D01*
G01X223574Y133338D02*
X221074D01*
Y134379D01*
X221199Y134713D01*
X221366Y134921D01*
X221699Y135004D01*
X222032Y134921D01*
X222241Y134671D01*
X222366Y134379D01*
Y133338D01*
G01Y134379D02*
X223574Y135004D01*
G01X221491Y136479D02*
X221241Y136729D01*
X221116Y137021D01*
X221074Y137354D01*
X221157Y137771D01*
X221366Y138063D01*
X221616Y138146D01*
X221866Y138104D01*
X222074Y137938D01*
X222491Y137104D01*
X222782Y136729D01*
X223199Y136479D01*
X223574Y136396D01*
Y138146D01*
G01X223074Y139454D02*
X223366Y139704D01*
X223532Y140038D01*
X223574Y140413D01*
X223532Y140746D01*
X223324Y141079D01*
X223074Y141288D01*
X222824Y141329D01*
X222532Y141246D01*
X222324Y140954D01*
X222241Y140663D01*
Y140288D01*
G01Y140663D02*
X222116Y140913D01*
X221907Y141121D01*
X221657Y141204D01*
X221407Y141121D01*
X221199Y140913D01*
X221074Y140538D01*
X221116Y140163D01*
X221282Y139788D01*
G01X213516Y130385D02*
X217516D01*
Y137785D01*
G01X157467Y77600D02*
Y80100D01*
X158508D01*
X158842Y79975D01*
X159050Y79808D01*
X159133Y79475D01*
X159050Y79142D01*
X158800Y78933D01*
X158508Y78808D01*
X157467D01*
G01X158508D02*
X159133Y77600D01*
G01X161400D02*
Y80100D01*
X160900Y79600D01*
G01Y77600D02*
X161900D01*
G01X163583Y78100D02*
X163833Y77808D01*
X164167Y77642D01*
X164542Y77600D01*
X164875Y77642D01*
X165208Y77850D01*
X165417Y78100D01*
X165458Y78350D01*
X165375Y78642D01*
X165083Y78850D01*
X164792Y78933D01*
X164417D01*
G01X164792D02*
X165042Y79058D01*
X165250Y79267D01*
X165333Y79517D01*
X165250Y79767D01*
X165042Y79975D01*
X164667Y80100D01*
X164292Y80058D01*
X163917Y79892D01*
G01X170936Y81413D02*
X166936D01*
Y74013D01*
G01X221951Y145359D02*
X221826Y145109D01*
X221743Y144817D01*
Y144484D01*
X221868Y144109D01*
X222076Y143817D01*
X222326Y143609D01*
X222743Y143442D01*
X223118Y143400D01*
X223493Y143484D01*
X223743Y143609D01*
X223993Y143859D01*
X224160Y144150D01*
X224243Y144442D01*
Y144734D01*
X224160Y145025D01*
X224035Y145275D01*
X223868Y145484D01*
G01X224243Y147542D02*
X221743D01*
X222243Y147042D01*
G01X224243D02*
Y148042D01*
G01X223743Y149725D02*
X224035Y149975D01*
X224201Y150309D01*
X224243Y150684D01*
X224201Y151017D01*
X223993Y151350D01*
X223743Y151559D01*
X223493Y151600D01*
X223201Y151517D01*
X222993Y151225D01*
X222910Y150934D01*
Y150559D01*
G01Y150934D02*
X222785Y151184D01*
X222576Y151392D01*
X222326Y151475D01*
X222076Y151392D01*
X221868Y151184D01*
X221743Y150809D01*
X221785Y150434D01*
X221951Y150059D01*
G01X217617Y100792D02*
X217367Y100917D01*
X217075Y101000D01*
X216742D01*
X216367Y100875D01*
X216075Y100667D01*
X215867Y100417D01*
X215700Y100000D01*
X215658Y99625D01*
X215742Y99250D01*
X215867Y99000D01*
X216117Y98750D01*
X216408Y98583D01*
X216700Y98500D01*
X216992D01*
X217283Y98583D01*
X217533Y98708D01*
X217742Y98875D01*
G01X219008Y100583D02*
X219258Y100833D01*
X219550Y100958D01*
X219883Y101000D01*
X220300Y100917D01*
X220592Y100708D01*
X220675Y100458D01*
X220633Y100208D01*
X220467Y100000D01*
X219633Y99583D01*
X219258Y99292D01*
X219008Y98875D01*
X218925Y98500D01*
X220675D01*
G01X222900D02*
X223192Y98542D01*
X223525Y98667D01*
X223733Y98875D01*
X223817Y99167D01*
X223733Y99458D01*
X223483Y99708D01*
X223108Y99833D01*
X222692D01*
X222442Y99917D01*
X222233Y100125D01*
X222150Y100417D01*
X222275Y100708D01*
X222567Y100917D01*
X222900Y101000D01*
X223233Y100917D01*
X223525Y100708D01*
X223650Y100417D01*
X223567Y100125D01*
X223358Y99917D01*
X223108Y99833D01*
X222692D01*
X222317Y99708D01*
X222067Y99458D01*
X221983Y99167D01*
X222067Y98875D01*
X222275Y98667D01*
X222608Y98542D01*
X222900Y98500D01*
G01X187217Y99392D02*
X186967Y99517D01*
X186675Y99600D01*
X186342D01*
X185967Y99475D01*
X185675Y99267D01*
X185467Y99017D01*
X185300Y98600D01*
X185258Y98225D01*
X185342Y97850D01*
X185467Y97600D01*
X185717Y97350D01*
X186008Y97183D01*
X186300Y97100D01*
X186592D01*
X186883Y97183D01*
X187133Y97308D01*
X187342Y97475D01*
G01X188608Y99183D02*
X188858Y99433D01*
X189150Y99558D01*
X189483Y99600D01*
X189900Y99517D01*
X190192Y99308D01*
X190275Y99058D01*
X190233Y98808D01*
X190067Y98600D01*
X189233Y98183D01*
X188858Y97892D01*
X188608Y97475D01*
X188525Y97100D01*
X190275D01*
G01X191583Y97600D02*
X191833Y97308D01*
X192167Y97142D01*
X192542Y97100D01*
X192875Y97142D01*
X193208Y97350D01*
X193417Y97600D01*
X193458Y97850D01*
X193375Y98142D01*
X193083Y98350D01*
X192792Y98433D01*
X192417D01*
G01X192792D02*
X193042Y98558D01*
X193250Y98767D01*
X193333Y99017D01*
X193250Y99267D01*
X193042Y99475D01*
X192667Y99600D01*
X192292Y99558D01*
X191917Y99392D01*
G01X163808Y90717D02*
X163683Y90467D01*
X163600Y90175D01*
Y89842D01*
X163725Y89467D01*
X163933Y89175D01*
X164183Y88967D01*
X164600Y88800D01*
X164975Y88758D01*
X165350Y88842D01*
X165600Y88967D01*
X165850Y89217D01*
X166017Y89508D01*
X166100Y89800D01*
Y90092D01*
X166017Y90383D01*
X165892Y90633D01*
X165725Y90842D01*
G01X164017Y92108D02*
X163767Y92358D01*
X163642Y92650D01*
X163600Y92983D01*
X163683Y93400D01*
X163892Y93692D01*
X164142Y93775D01*
X164392Y93733D01*
X164600Y93567D01*
X165017Y92733D01*
X165308Y92358D01*
X165725Y92108D01*
X166100Y92025D01*
Y93775D01*
G01Y96500D02*
X163600D01*
X165392Y94958D01*
Y97042D01*
G01X222017Y108392D02*
X221767Y108517D01*
X221475Y108600D01*
X221142D01*
X220767Y108475D01*
X220475Y108267D01*
X220267Y108017D01*
X220100Y107600D01*
X220058Y107225D01*
X220142Y106850D01*
X220267Y106600D01*
X220517Y106350D01*
X220808Y106183D01*
X221100Y106100D01*
X221392D01*
X221683Y106183D01*
X221933Y106308D01*
X222142Y106475D01*
G01X224200Y106100D02*
Y108600D01*
X223700Y108100D01*
G01Y106100D02*
X224700D01*
G01X227300D02*
X227592Y106142D01*
X227925Y106267D01*
X228133Y106475D01*
X228217Y106767D01*
X228133Y107058D01*
X227883Y107308D01*
X227508Y107433D01*
X227092D01*
X226842Y107517D01*
X226633Y107725D01*
X226550Y108017D01*
X226675Y108308D01*
X226967Y108517D01*
X227300Y108600D01*
X227633Y108517D01*
X227925Y108308D01*
X228050Y108017D01*
X227967Y107725D01*
X227758Y107517D01*
X227508Y107433D01*
X227092D01*
X226717Y107308D01*
X226467Y107058D01*
X226383Y106767D01*
X226467Y106475D01*
X226675Y106267D01*
X227008Y106142D01*
X227300Y106100D01*
G01X172820Y124595D02*
Y132495D01*
X179320D01*
Y143095D01*
X172820D01*
Y150995D01*
X212220D01*
Y143095D01*
X205720D01*
Y132495D01*
X212220D01*
Y124595D01*
X172820D01*
G01X224438Y221779D02*
X221938D01*
Y222613D01*
X222063Y222946D01*
X222230Y223196D01*
X222480Y223404D01*
X222771Y223571D01*
X223188Y223613D01*
X223605Y223571D01*
X223896Y223404D01*
X224146Y223196D01*
X224313Y222946D01*
X224438Y222613D01*
Y221779D01*
G01X222355Y225004D02*
X222105Y225254D01*
X221980Y225546D01*
X221938Y225879D01*
X222021Y226296D01*
X222230Y226588D01*
X222480Y226671D01*
X222730Y226629D01*
X222938Y226463D01*
X223355Y225629D01*
X223646Y225254D01*
X224063Y225004D01*
X224438Y224921D01*
Y226671D01*
G01X211671Y229730D02*
Y218430D01*
X219971D01*
Y229730D01*
X211671D01*
G01X171597Y164860D02*
Y162360D01*
X173263D01*
G01X176363D02*
X174697D01*
Y164860D01*
X176363D01*
G01X175697Y163652D02*
X174697D01*
G01X177713Y162360D02*
Y164860D01*
X178547D01*
X178880Y164735D01*
X179130Y164568D01*
X179338Y164318D01*
X179505Y164027D01*
X179547Y163610D01*
X179505Y163193D01*
X179338Y162902D01*
X179130Y162652D01*
X178880Y162485D01*
X178547Y162360D01*
X177713D01*
G01X180938Y164443D02*
X181188Y164693D01*
X181480Y164818D01*
X181813Y164860D01*
X182230Y164777D01*
X182522Y164568D01*
X182605Y164318D01*
X182563Y164068D01*
X182397Y163860D01*
X181563Y163443D01*
X181188Y163152D01*
X180938Y162735D01*
X180855Y162360D01*
X182605D01*
G01X189583Y178728D02*
X191583D01*
G01X187583D02*
X185583D01*
G01X189583Y176728D02*
Y180728D01*
G01X187583Y176728D02*
Y180728D01*
X189583Y178728D01*
X187583Y176728D01*
G01X195483Y175927D02*
G02Y170529I-1900J-2699D01*
G01Y167606D01*
G02Y178850I-6900J5622D01*
G01Y175927D01*
G01X201367Y153467D02*
Y155967D01*
X202408D01*
X202742Y155842D01*
X202950Y155675D01*
X203033Y155342D01*
X202950Y155009D01*
X202700Y154800D01*
X202408Y154675D01*
X201367D01*
G01X202408D02*
X203033Y153467D01*
G01X204508Y155550D02*
X204758Y155800D01*
X205050Y155925D01*
X205383Y155967D01*
X205800Y155884D01*
X206092Y155675D01*
X206175Y155425D01*
X206133Y155175D01*
X205967Y154967D01*
X205133Y154550D01*
X204758Y154259D01*
X204508Y153842D01*
X204425Y153467D01*
X206175D01*
G01X207608Y154509D02*
X207900Y154800D01*
X208150Y154967D01*
X208483Y155050D01*
X208775Y154967D01*
X208983Y154800D01*
X209150Y154550D01*
X209192Y154259D01*
X209150Y154009D01*
X208983Y153759D01*
X208733Y153550D01*
X208442Y153467D01*
X208108Y153550D01*
X207817Y153800D01*
X207650Y154175D01*
X207608Y154592D01*
X207692Y155134D01*
X207817Y155425D01*
X208025Y155717D01*
X208317Y155925D01*
X208608Y155967D01*
X208900Y155884D01*
X209108Y155675D01*
G01X172360Y192289D02*
Y189789D01*
G01X171402Y192289D02*
X173318D01*
G01X174627Y189789D02*
Y192289D01*
X175627D01*
X175960Y192164D01*
X176210Y191872D01*
X176293Y191539D01*
X176210Y191206D01*
X176002Y190956D01*
X175627Y190831D01*
X174627D01*
G01X178560Y189789D02*
X178852Y189831D01*
X179185Y189956D01*
X179393Y190164D01*
X179477Y190456D01*
X179393Y190747D01*
X179143Y190997D01*
X178768Y191122D01*
X178352D01*
X178102Y191206D01*
X177893Y191414D01*
X177810Y191706D01*
X177935Y191997D01*
X178227Y192206D01*
X178560Y192289D01*
X178893Y192206D01*
X179185Y191997D01*
X179310Y191706D01*
X179227Y191414D01*
X179018Y191206D01*
X178768Y191122D01*
X178352D01*
X177977Y190997D01*
X177727Y190747D01*
X177643Y190456D01*
X177727Y190164D01*
X177935Y189956D01*
X178268Y189831D01*
X178560Y189789D01*
G01X180616Y202509D02*
Y200717D01*
X180783Y200342D01*
X181116Y200092D01*
X181533Y200009D01*
X181950Y200092D01*
X182283Y200342D01*
X182450Y200717D01*
Y202509D01*
G01X184633Y200009D02*
X184925Y200051D01*
X185258Y200176D01*
X185466Y200384D01*
X185550Y200676D01*
X185466Y200967D01*
X185216Y201217D01*
X184841Y201342D01*
X184425D01*
X184175Y201426D01*
X183966Y201634D01*
X183883Y201926D01*
X184008Y202217D01*
X184300Y202426D01*
X184633Y202509D01*
X184966Y202426D01*
X185258Y202217D01*
X185383Y201926D01*
X185300Y201634D01*
X185091Y201426D01*
X184841Y201342D01*
X184425D01*
X184050Y201217D01*
X183800Y200967D01*
X183716Y200676D01*
X183800Y200384D01*
X184008Y200176D01*
X184341Y200051D01*
X184633Y200009D01*
G01X195500Y187850D02*
X203500D01*
Y199800D01*
X195500D01*
Y187850D01*
G01X201650Y199800D02*
X199650Y197800D01*
X197650Y199800D01*
G01X208070Y204670D02*
X176970D01*
Y267770D01*
X208070D01*
Y204670D01*
G01X171422Y202318D02*
Y199818D01*
G01X170464Y202318D02*
X172380D01*
G01X173689Y199818D02*
Y202318D01*
X174689D01*
X175022Y202193D01*
X175272Y201901D01*
X175355Y201568D01*
X175272Y201235D01*
X175064Y200985D01*
X174689Y200860D01*
X173689D01*
G01X176705Y200193D02*
X176955Y199985D01*
X177247Y199860D01*
X177622Y199818D01*
X177997Y199901D01*
X178289Y200068D01*
X178497Y200360D01*
X178539Y200693D01*
X178455Y201026D01*
X178247Y201235D01*
X177955Y201401D01*
X177664Y201443D01*
X177372Y201401D01*
X176997Y201235D01*
X177122Y202318D01*
X178247D01*
G01X172696Y182239D02*
Y179739D01*
G01X171738Y182239D02*
X173654D01*
G01X174963Y179739D02*
Y182239D01*
X175963D01*
X176296Y182114D01*
X176546Y181822D01*
X176629Y181489D01*
X176546Y181156D01*
X176338Y180906D01*
X175963Y180781D01*
X174963D01*
G01X179396Y179739D02*
Y182239D01*
X177854Y180447D01*
X179938D01*
G01X204162Y161090D02*
X201662D01*
Y162131D01*
X201787Y162465D01*
X201954Y162673D01*
X202287Y162756D01*
X202620Y162673D01*
X202829Y162423D01*
X202954Y162131D01*
Y161090D01*
G01Y162131D02*
X204162Y162756D01*
G01X203662Y164106D02*
X203954Y164356D01*
X204120Y164690D01*
X204162Y165065D01*
X204120Y165398D01*
X203912Y165731D01*
X203662Y165940D01*
X203412Y165981D01*
X203120Y165898D01*
X202912Y165606D01*
X202829Y165315D01*
Y164940D01*
G01Y165315D02*
X202704Y165565D01*
X202495Y165773D01*
X202245Y165856D01*
X201995Y165773D01*
X201787Y165565D01*
X201662Y165190D01*
X201704Y164815D01*
X201870Y164440D01*
G01X204162Y168123D02*
X204120Y168415D01*
X203995Y168748D01*
X203787Y168956D01*
X203495Y169040D01*
X203204Y168956D01*
X202954Y168706D01*
X202829Y168331D01*
Y167915D01*
X202745Y167665D01*
X202537Y167456D01*
X202245Y167373D01*
X201954Y167498D01*
X201745Y167790D01*
X201662Y168123D01*
X201745Y168456D01*
X201954Y168748D01*
X202245Y168873D01*
X202537Y168790D01*
X202745Y168581D01*
X202829Y168331D01*
Y167915D01*
X202954Y167540D01*
X203204Y167290D01*
X203495Y167206D01*
X203787Y167290D01*
X203995Y167498D01*
X204120Y167831D01*
X204162Y168123D01*
G01X207500Y178100D02*
X203500D01*
Y170700D01*
G01X212300Y161067D02*
X209800D01*
Y162108D01*
X209925Y162442D01*
X210092Y162650D01*
X210425Y162733D01*
X210758Y162650D01*
X210967Y162400D01*
X211092Y162108D01*
Y161067D01*
G01Y162108D02*
X212300Y162733D01*
G01X211800Y164083D02*
X212092Y164333D01*
X212258Y164667D01*
X212300Y165042D01*
X212258Y165375D01*
X212050Y165708D01*
X211800Y165917D01*
X211550Y165958D01*
X211258Y165875D01*
X211050Y165583D01*
X210967Y165292D01*
Y164917D01*
G01Y165292D02*
X210842Y165542D01*
X210633Y165750D01*
X210383Y165833D01*
X210133Y165750D01*
X209925Y165542D01*
X209800Y165167D01*
X209842Y164792D01*
X210008Y164417D01*
G01X212008Y167392D02*
X212217Y167683D01*
X212300Y168017D01*
X212217Y168350D01*
X211967Y168642D01*
X211592Y168850D01*
X211217Y168933D01*
X210758D01*
X210383Y168850D01*
X210050Y168642D01*
X209883Y168392D01*
X209800Y168100D01*
X209883Y167767D01*
X210050Y167517D01*
X210300Y167350D01*
X210633Y167267D01*
X210925Y167350D01*
X211217Y167558D01*
X211383Y167808D01*
X211425Y168100D01*
X211342Y168433D01*
X211133Y168683D01*
X210758Y168933D01*
G01X211900Y178100D02*
X207900D01*
Y170700D01*
G01X214935Y167840D02*
Y170340D01*
X215976D01*
X216310Y170215D01*
X216518Y170048D01*
X216601Y169715D01*
X216518Y169382D01*
X216268Y169173D01*
X215976Y169048D01*
X214935D01*
G01X215976D02*
X216601Y167840D01*
G01X217951Y168340D02*
X218201Y168048D01*
X218535Y167882D01*
X218910Y167840D01*
X219243Y167882D01*
X219576Y168090D01*
X219785Y168340D01*
X219826Y168590D01*
X219743Y168882D01*
X219451Y169090D01*
X219160Y169173D01*
X218785D01*
G01X219160D02*
X219410Y169298D01*
X219618Y169507D01*
X219701Y169757D01*
X219618Y170007D01*
X219410Y170215D01*
X219035Y170340D01*
X218660Y170298D01*
X218285Y170132D01*
G01X221885Y167840D02*
X221968Y168382D01*
X222093Y168840D01*
X222260Y169257D01*
X222468Y169715D01*
X222801Y170340D01*
X221135D01*
G01X213700Y183300D02*
Y179300D01*
X221100D01*
G01X215245Y174990D02*
Y177490D01*
X216286D01*
X216620Y177365D01*
X216828Y177198D01*
X216911Y176865D01*
X216828Y176532D01*
X216578Y176323D01*
X216286Y176198D01*
X215245D01*
G01X216286D02*
X216911Y174990D01*
G01X219678D02*
Y177490D01*
X218136Y175698D01*
X220220D01*
G01X222278Y177490D02*
X221945Y177407D01*
X221695Y177198D01*
X221528Y176948D01*
X221403Y176615D01*
X221361Y176240D01*
X221403Y175865D01*
X221528Y175532D01*
X221695Y175282D01*
X221945Y175073D01*
X222278Y174990D01*
X222611Y175073D01*
X222861Y175282D01*
X223028Y175532D01*
X223153Y175865D01*
X223195Y176240D01*
X223153Y176615D01*
X223028Y176948D01*
X222861Y177198D01*
X222611Y177407D01*
X222278Y177490D01*
G01X213700Y199300D02*
Y195300D01*
X221100D01*
G01X221200Y183350D02*
X225200D01*
Y190750D01*
G01X214935Y171440D02*
Y173940D01*
X215976D01*
X216310Y173815D01*
X216518Y173648D01*
X216601Y173315D01*
X216518Y172982D01*
X216268Y172773D01*
X215976Y172648D01*
X214935D01*
G01X215976D02*
X216601Y171440D01*
G01X219368D02*
Y173940D01*
X217826Y172148D01*
X219910D01*
G01X221176Y173523D02*
X221426Y173773D01*
X221718Y173898D01*
X222051Y173940D01*
X222468Y173857D01*
X222760Y173648D01*
X222843Y173398D01*
X222801Y173148D01*
X222635Y172940D01*
X221801Y172523D01*
X221426Y172232D01*
X221176Y171815D01*
X221093Y171440D01*
X222843D01*
G01X221100Y183300D02*
Y187300D01*
X213700D01*
G01X221200Y190900D02*
X225200D01*
Y198300D01*
G01X212067Y210000D02*
Y212500D01*
X213108D01*
X213442Y212375D01*
X213650Y212208D01*
X213733Y211875D01*
X213650Y211542D01*
X213400Y211333D01*
X213108Y211208D01*
X212067D01*
G01X213108D02*
X213733Y210000D01*
G01X215083Y210500D02*
X215333Y210208D01*
X215667Y210042D01*
X216042Y210000D01*
X216375Y210042D01*
X216708Y210250D01*
X216917Y210500D01*
X216958Y210750D01*
X216875Y211042D01*
X216583Y211250D01*
X216292Y211333D01*
X215917D01*
G01X216292D02*
X216542Y211458D01*
X216750Y211667D01*
X216833Y211917D01*
X216750Y212167D01*
X216542Y212375D01*
X216167Y212500D01*
X215792Y212458D01*
X215417Y212292D01*
G01X218183Y210375D02*
X218433Y210167D01*
X218725Y210042D01*
X219100Y210000D01*
X219475Y210083D01*
X219767Y210250D01*
X219975Y210542D01*
X220017Y210875D01*
X219933Y211208D01*
X219725Y211417D01*
X219433Y211583D01*
X219142Y211625D01*
X218850Y211583D01*
X218475Y211417D01*
X218600Y212500D01*
X219725D01*
G01X212400Y208700D02*
Y204700D01*
X219800D01*
G01X222617Y207959D02*
X222367Y208084D01*
X222075Y208167D01*
X221742D01*
X221367Y208042D01*
X221075Y207834D01*
X220867Y207584D01*
X220700Y207167D01*
X220658Y206792D01*
X220742Y206417D01*
X220867Y206167D01*
X221117Y205917D01*
X221408Y205750D01*
X221700Y205667D01*
X221992D01*
X222283Y205750D01*
X222533Y205875D01*
X222742Y206042D01*
G01X224800Y205667D02*
Y208167D01*
X224300Y207667D01*
G01Y205667D02*
X225300D01*
G01X226983Y206042D02*
X227233Y205834D01*
X227525Y205709D01*
X227900Y205667D01*
X228275Y205750D01*
X228567Y205917D01*
X228775Y206209D01*
X228817Y206542D01*
X228733Y206875D01*
X228525Y207084D01*
X228233Y207250D01*
X227942Y207292D01*
X227650Y207250D01*
X227275Y207084D01*
X227400Y208167D01*
X228525D01*
G01X174613Y153734D02*
X174946Y153526D01*
X175321Y153401D01*
X175655D01*
X175988Y153526D01*
X176238Y153734D01*
X176363Y154026D01*
X176280Y154318D01*
X176071Y154568D01*
X175696Y154734D01*
X175196Y154818D01*
X174905Y154984D01*
X174780Y155276D01*
X174863Y155568D01*
X175071Y155776D01*
X175363Y155901D01*
X175655D01*
X175946Y155818D01*
X176196Y155609D01*
G01X177338Y155901D02*
X177921Y153401D01*
X178588Y155901D01*
X179255Y153401D01*
X179838Y155901D01*
G01X182188Y153401D02*
Y155901D01*
X180646Y154109D01*
X182730D01*
G01X221486Y276601D02*
X221236Y276726D01*
X220944Y276809D01*
X220611D01*
X220236Y276684D01*
X219944Y276476D01*
X219736Y276226D01*
X219569Y275809D01*
X219527Y275434D01*
X219611Y275059D01*
X219736Y274809D01*
X219986Y274559D01*
X220277Y274392D01*
X220569Y274309D01*
X220861D01*
X221152Y274392D01*
X221402Y274517D01*
X221611Y274684D01*
G01X223669Y274309D02*
Y276809D01*
X223169Y276309D01*
G01Y274309D02*
X224169D01*
G01X226686D02*
X226769Y274851D01*
X226894Y275309D01*
X227061Y275726D01*
X227269Y276184D01*
X227602Y276809D01*
X225936D01*
G01X211590Y280128D02*
X217090D01*
Y272128D01*
X211490D01*
G01X199490Y280128D02*
X204990D01*
G01X199490D02*
Y272128D01*
X204990D01*
G01X170388Y256379D02*
X172180D01*
X172555Y256546D01*
X172805Y256879D01*
X172888Y257296D01*
X172805Y257713D01*
X172555Y258046D01*
X172180Y258213D01*
X170388D01*
G01X172555Y259521D02*
X172763Y259854D01*
X172888Y260229D01*
Y260563D01*
X172763Y260896D01*
X172555Y261146D01*
X172263Y261271D01*
X171971Y261188D01*
X171721Y260979D01*
X171555Y260604D01*
X171471Y260104D01*
X171305Y259813D01*
X171013Y259688D01*
X170721Y259771D01*
X170513Y259979D01*
X170388Y260271D01*
Y260563D01*
X170471Y260854D01*
X170680Y261104D01*
G01X171555Y263829D02*
X171430Y263996D01*
X171221Y264121D01*
X170930Y264204D01*
X170680Y264121D01*
X170513Y263954D01*
X170388Y263663D01*
Y262538D01*
X172888D01*
Y263913D01*
X172721Y264204D01*
X172471Y264371D01*
X172180Y264454D01*
X171888Y264371D01*
X171638Y264121D01*
X171555Y263829D01*
Y262538D01*
G01X170805Y265804D02*
X170555Y266054D01*
X170430Y266346D01*
X170388Y266679D01*
X170471Y267096D01*
X170680Y267388D01*
X170930Y267471D01*
X171180Y267429D01*
X171388Y267263D01*
X171805Y266429D01*
X172096Y266054D01*
X172513Y265804D01*
X172888Y265721D01*
Y267471D01*
G01X219736Y278009D02*
Y280509D01*
X220777D01*
X221111Y280384D01*
X221319Y280217D01*
X221402Y279884D01*
X221319Y279551D01*
X221069Y279342D01*
X220777Y279217D01*
X219736D01*
G01X220777D02*
X221402Y278009D01*
G01X224169D02*
Y280509D01*
X222627Y278717D01*
X224711D01*
G01X225977Y279051D02*
X226269Y279342D01*
X226519Y279509D01*
X226852Y279592D01*
X227144Y279509D01*
X227352Y279342D01*
X227519Y279092D01*
X227561Y278801D01*
X227519Y278551D01*
X227352Y278301D01*
X227102Y278092D01*
X226811Y278009D01*
X226477Y278092D01*
X226186Y278342D01*
X226019Y278717D01*
X225977Y279134D01*
X226061Y279676D01*
X226186Y279967D01*
X226394Y280259D01*
X226686Y280467D01*
X226977Y280509D01*
X227269Y280426D01*
X227477Y280217D01*
G01X205167Y285448D02*
Y281448D01*
X212567D01*
G01X218723Y285945D02*
X222723D01*
Y293345D01*
G01X168581Y278681D02*
Y276181D01*
X170247D01*
G01X171597Y276681D02*
X171847Y276389D01*
X172181Y276223D01*
X172556Y276181D01*
X172889Y276223D01*
X173222Y276431D01*
X173431Y276681D01*
X173472Y276931D01*
X173389Y277223D01*
X173097Y277431D01*
X172806Y277514D01*
X172431D01*
G01X172806D02*
X173056Y277639D01*
X173264Y277848D01*
X173347Y278098D01*
X173264Y278348D01*
X173056Y278556D01*
X172681Y278681D01*
X172306Y278639D01*
X171931Y278473D01*
G01X189220Y280081D02*
X175820D01*
G01X189220Y272881D02*
Y280081D01*
G01X175820Y272881D02*
X189220D01*
G01X175820Y280081D02*
Y272881D01*
G01X202237Y289493D02*
X202112Y289243D01*
X202029Y288951D01*
Y288618D01*
X202154Y288243D01*
X202362Y287951D01*
X202612Y287743D01*
X203029Y287576D01*
X203404Y287534D01*
X203779Y287618D01*
X204029Y287743D01*
X204279Y287993D01*
X204446Y288284D01*
X204529Y288576D01*
Y288868D01*
X204446Y289159D01*
X204321Y289409D01*
X204154Y289618D01*
G01X204237Y290968D02*
X204446Y291259D01*
X204529Y291593D01*
X204446Y291926D01*
X204196Y292218D01*
X203821Y292426D01*
X203446Y292509D01*
X202987D01*
X202612Y292426D01*
X202279Y292218D01*
X202112Y291968D01*
X202029Y291676D01*
X202112Y291343D01*
X202279Y291093D01*
X202529Y290926D01*
X202862Y290843D01*
X203154Y290926D01*
X203446Y291134D01*
X203612Y291384D01*
X203654Y291676D01*
X203571Y292009D01*
X203362Y292259D01*
X202987Y292509D01*
G01X205937Y289493D02*
X205812Y289243D01*
X205729Y288951D01*
Y288618D01*
X205854Y288243D01*
X206062Y287951D01*
X206312Y287743D01*
X206729Y287576D01*
X207104Y287534D01*
X207479Y287618D01*
X207729Y287743D01*
X207979Y287993D01*
X208146Y288284D01*
X208229Y288576D01*
Y288868D01*
X208146Y289159D01*
X208021Y289409D01*
X207854Y289618D01*
G01X208229Y291676D02*
X208187Y291968D01*
X208062Y292301D01*
X207854Y292509D01*
X207562Y292593D01*
X207271Y292509D01*
X207021Y292259D01*
X206896Y291884D01*
Y291468D01*
X206812Y291218D01*
X206604Y291009D01*
X206312Y290926D01*
X206021Y291051D01*
X205812Y291343D01*
X205729Y291676D01*
X205812Y292009D01*
X206021Y292301D01*
X206312Y292426D01*
X206604Y292343D01*
X206812Y292134D01*
X206896Y291884D01*
Y291468D01*
X207021Y291093D01*
X207271Y290843D01*
X207562Y290759D01*
X207854Y290843D01*
X208062Y291051D01*
X208187Y291384D01*
X208229Y291676D01*
G01X209637Y289493D02*
X209512Y289243D01*
X209429Y288951D01*
Y288618D01*
X209554Y288243D01*
X209762Y287951D01*
X210012Y287743D01*
X210429Y287576D01*
X210804Y287534D01*
X211179Y287618D01*
X211429Y287743D01*
X211679Y287993D01*
X211846Y288284D01*
X211929Y288576D01*
Y288868D01*
X211846Y289159D01*
X211721Y289409D01*
X211554Y289618D01*
G01X211929Y291593D02*
X211387Y291676D01*
X210929Y291801D01*
X210512Y291968D01*
X210054Y292176D01*
X209429Y292509D01*
Y290843D01*
G01X201397Y294292D02*
G02X183643I-8877J18700D01*
G01X173820D01*
Y304115D01*
G02X172053Y309892I18700J8878D01*
G01X169720D01*
Y316092D01*
X172053D01*
G02X173820Y321869I20467J-3101D01*
G01Y331692D01*
X183643D01*
G02X201397I8877J-18700D01*
G01X211220D01*
Y321869D01*
G02X212987Y316092I-18700J-8878D01*
G01X215320D01*
Y309892D01*
X212987D01*
G02X211220Y304115I-20467J3101D01*
G01Y294292D01*
X201397D01*
G01X175490Y282449D02*
X172990D01*
Y283283D01*
X173115Y283616D01*
X173282Y283866D01*
X173532Y284074D01*
X173823Y284241D01*
X174240Y284283D01*
X174657Y284241D01*
X174948Y284074D01*
X175198Y283866D01*
X175365Y283616D01*
X175490Y283283D01*
Y282449D01*
G01Y286966D02*
X172990D01*
X174782Y285424D01*
Y287508D01*
G01X220089Y319231D02*
X224289D01*
G01X220089Y307531D02*
Y319231D01*
G01X224289Y307531D02*
X220089D01*
G01X174336Y333939D02*
X174669Y333731D01*
X175044Y333606D01*
X175378D01*
X175711Y333731D01*
X175961Y333939D01*
X176086Y334231D01*
X176003Y334523D01*
X175794Y334773D01*
X175419Y334939D01*
X174919Y335023D01*
X174628Y335189D01*
X174503Y335481D01*
X174586Y335773D01*
X174794Y335981D01*
X175086Y336106D01*
X175378D01*
X175669Y336023D01*
X175919Y335814D01*
G01X177061Y336106D02*
X177644Y333606D01*
X178311Y336106D01*
X178978Y333606D01*
X179561Y336106D01*
G01X180619Y335689D02*
X180869Y335939D01*
X181161Y336064D01*
X181494Y336106D01*
X181911Y336023D01*
X182203Y335814D01*
X182286Y335564D01*
X182244Y335314D01*
X182078Y335106D01*
X181244Y334689D01*
X180869Y334398D01*
X180619Y333981D01*
X180536Y333606D01*
X182286D01*
G01X192520Y317292D02*
Y314792D01*
G01X195348Y315820D02*
G02X192520Y308992I-2828J-2828D01*
G01D02*
G02X189692Y315820I0J4000D01*
G01X196064Y343847D02*
Y351647D01*
X208664D01*
Y343847D01*
X196064D01*
G01X199564Y350247D02*
X198964Y350147D01*
X198464Y349647D01*
X198064Y349147D01*
X197864Y348547D01*
X197764Y347747D01*
X197864Y347047D01*
X198064Y346347D01*
X198464Y345847D01*
X198964Y345447D01*
X199564Y345247D01*
X200264Y345447D01*
X200764Y345847D01*
X201064Y346347D01*
X201364Y347047D01*
X201464Y347747D01*
X201364Y348547D01*
X201064Y349147D01*
X200764Y349647D01*
X200264Y350147D01*
X199564Y350247D01*
G01X205164Y345247D02*
Y350247D01*
X204164Y349247D01*
G01Y345247D02*
X206164D01*
G01X196064Y732430D02*
Y740230D01*
X208664D01*
Y732430D01*
X196064D01*
G01X199564Y738830D02*
X198964Y738730D01*
X198464Y738230D01*
X198064Y737730D01*
X197864Y737130D01*
X197764Y736330D01*
X197864Y735630D01*
X198064Y734930D01*
X198464Y734430D01*
X198964Y734030D01*
X199564Y733830D01*
X200264Y734030D01*
X200764Y734430D01*
X201064Y734930D01*
X201364Y735630D01*
X201464Y736330D01*
X201364Y737130D01*
X201064Y737730D01*
X200764Y738230D01*
X200264Y738730D01*
X199564Y738830D01*
G01X203364Y734830D02*
X203864Y734230D01*
X204564Y733930D01*
X205264Y733830D01*
X205964Y733930D01*
X206564Y734330D01*
X207064Y734830D01*
Y735330D01*
X206964Y735930D01*
X206364Y736330D01*
X205764Y736530D01*
X205064D01*
G01X205764D02*
X206264Y736730D01*
X206664Y737230D01*
X206864Y737730D01*
X206664Y738230D01*
X206264Y738630D01*
X205564Y738830D01*
X204764Y738730D01*
X204064Y738430D01*
G01X285039Y-15895D02*
Y-23695D01*
X272439D01*
Y-15895D01*
X285039D01*
G01X281539Y-22295D02*
X282139Y-22195D01*
X282639Y-21695D01*
X283039Y-21195D01*
X283239Y-20595D01*
X283339Y-19795D01*
X283239Y-19095D01*
X283039Y-18395D01*
X282639Y-17895D01*
X282139Y-17495D01*
X281539Y-17295D01*
X280839Y-17495D01*
X280339Y-17895D01*
X280039Y-18395D01*
X279739Y-19095D01*
X279639Y-19795D01*
X279739Y-20595D01*
X280039Y-21195D01*
X280339Y-21695D01*
X280839Y-22195D01*
X281539Y-22295D01*
G01X277539Y-21495D02*
X277039Y-21995D01*
X276439Y-22195D01*
X275739Y-22295D01*
X274939Y-22195D01*
X274339Y-21695D01*
X274139Y-21195D01*
X274239Y-20695D01*
X274539Y-20295D01*
X276239Y-19495D01*
X277039Y-18895D01*
X277539Y-18095D01*
X277639Y-17295D01*
X274139D01*
G01X229000Y64467D02*
X226500D01*
Y65508D01*
X226625Y65842D01*
X226792Y66050D01*
X227125Y66133D01*
X227458Y66050D01*
X227667Y65800D01*
X227792Y65508D01*
Y64467D01*
G01Y65508D02*
X229000Y66133D01*
G01X227958Y67608D02*
X227667Y67900D01*
X227500Y68150D01*
X227417Y68483D01*
X227500Y68775D01*
X227667Y68983D01*
X227917Y69150D01*
X228208Y69192D01*
X228458Y69150D01*
X228708Y68983D01*
X228917Y68733D01*
X229000Y68442D01*
X228917Y68108D01*
X228667Y67817D01*
X228292Y67650D01*
X227875Y67608D01*
X227333Y67692D01*
X227042Y67817D01*
X226750Y68025D01*
X226542Y68317D01*
X226500Y68608D01*
X226583Y68900D01*
X226792Y69108D01*
G01X229000Y71500D02*
X228958Y71792D01*
X228833Y72125D01*
X228625Y72333D01*
X228333Y72417D01*
X228042Y72333D01*
X227792Y72083D01*
X227667Y71708D01*
Y71292D01*
X227583Y71042D01*
X227375Y70833D01*
X227083Y70750D01*
X226792Y70875D01*
X226583Y71167D01*
X226500Y71500D01*
X226583Y71833D01*
X226792Y72125D01*
X227083Y72250D01*
X227375Y72167D01*
X227583Y71958D01*
X227667Y71708D01*
Y71292D01*
X227792Y70917D01*
X228042Y70667D01*
X228333Y70583D01*
X228625Y70667D01*
X228833Y70875D01*
X228958Y71208D01*
X229000Y71500D01*
G01X228500Y37067D02*
X226000D01*
Y38108D01*
X226125Y38442D01*
X226292Y38650D01*
X226625Y38733D01*
X226958Y38650D01*
X227167Y38400D01*
X227292Y38108D01*
Y37067D01*
G01Y38108D02*
X228500Y38733D01*
G01Y40917D02*
X227958Y41000D01*
X227500Y41125D01*
X227083Y41292D01*
X226625Y41500D01*
X226000Y41833D01*
Y40167D01*
G01X228500Y44100D02*
X226000D01*
X226500Y43600D01*
G01X228500D02*
Y44600D01*
G01X230800Y27567D02*
X228300D01*
Y28608D01*
X228425Y28942D01*
X228592Y29150D01*
X228925Y29233D01*
X229258Y29150D01*
X229467Y28900D01*
X229592Y28608D01*
Y27567D01*
G01Y28608D02*
X230800Y29233D01*
G01Y31417D02*
X230258Y31500D01*
X229800Y31625D01*
X229383Y31792D01*
X228925Y32000D01*
X228300Y32333D01*
Y30667D01*
G01X228717Y33808D02*
X228467Y34058D01*
X228342Y34350D01*
X228300Y34683D01*
X228383Y35100D01*
X228592Y35392D01*
X228842Y35475D01*
X229092Y35433D01*
X229300Y35267D01*
X229717Y34433D01*
X230008Y34058D01*
X230425Y33808D01*
X230800Y33725D01*
Y35475D01*
G01X228634Y12867D02*
X226134D01*
Y13908D01*
X226259Y14242D01*
X226426Y14450D01*
X226759Y14533D01*
X227092Y14450D01*
X227301Y14200D01*
X227426Y13908D01*
Y12867D01*
G01Y13908D02*
X228634Y14533D01*
G01Y16717D02*
X228092Y16800D01*
X227634Y16925D01*
X227217Y17092D01*
X226759Y17300D01*
X226134Y17633D01*
Y15967D01*
G01X228134Y18983D02*
X228426Y19233D01*
X228592Y19567D01*
X228634Y19942D01*
X228592Y20275D01*
X228384Y20608D01*
X228134Y20817D01*
X227884Y20858D01*
X227592Y20775D01*
X227384Y20483D01*
X227301Y20192D01*
Y19817D01*
G01Y20192D02*
X227176Y20442D01*
X226967Y20650D01*
X226717Y20733D01*
X226467Y20650D01*
X226259Y20442D01*
X226134Y20067D01*
X226176Y19692D01*
X226342Y19317D01*
G01X228500Y57517D02*
X226000D01*
Y58558D01*
X226125Y58892D01*
X226292Y59100D01*
X226625Y59183D01*
X226958Y59100D01*
X227167Y58850D01*
X227292Y58558D01*
Y57517D01*
G01Y58558D02*
X228500Y59183D01*
G01X228208Y60742D02*
X228417Y61033D01*
X228500Y61367D01*
X228417Y61700D01*
X228167Y61992D01*
X227792Y62200D01*
X227417Y62283D01*
X226958D01*
X226583Y62200D01*
X226250Y61992D01*
X226083Y61742D01*
X226000Y61450D01*
X226083Y61117D01*
X226250Y60867D01*
X226500Y60700D01*
X226833Y60617D01*
X227125Y60700D01*
X227417Y60908D01*
X227583Y61158D01*
X227625Y61450D01*
X227542Y61783D01*
X227333Y62033D01*
X226958Y62283D01*
G01X227000Y46967D02*
X224500D01*
Y48008D01*
X224625Y48342D01*
X224792Y48550D01*
X225125Y48633D01*
X225458Y48550D01*
X225667Y48300D01*
X225792Y48008D01*
Y46967D01*
G01Y48008D02*
X227000Y48633D01*
G01Y50900D02*
X224500D01*
X225000Y50400D01*
G01X227000D02*
Y51400D01*
G01X224500Y54000D02*
X224583Y53667D01*
X224792Y53417D01*
X225042Y53250D01*
X225375Y53125D01*
X225750Y53083D01*
X226125Y53125D01*
X226458Y53250D01*
X226708Y53417D01*
X226917Y53667D01*
X227000Y54000D01*
X226917Y54333D01*
X226708Y54583D01*
X226458Y54750D01*
X226125Y54875D01*
X225750Y54917D01*
X225375Y54875D01*
X225042Y54750D01*
X224792Y54583D01*
X224583Y54333D01*
X224500Y54000D01*
G01X229222Y181901D02*
X226722D01*
Y182942D01*
X226847Y183276D01*
X227014Y183484D01*
X227347Y183567D01*
X227680Y183484D01*
X227889Y183234D01*
X228014Y182942D01*
Y181901D01*
G01Y182942D02*
X229222Y183567D01*
G01Y186334D02*
X226722D01*
X228514Y184792D01*
Y186876D01*
G01X229222Y188934D02*
X226722D01*
X227222Y188434D01*
G01X229222D02*
Y189434D01*
G01X229190Y191395D02*
X226690D01*
Y192436D01*
X226815Y192770D01*
X226982Y192978D01*
X227315Y193061D01*
X227648Y192978D01*
X227857Y192728D01*
X227982Y192436D01*
Y191395D01*
G01Y192436D02*
X229190Y193061D01*
G01X228690Y194411D02*
X228982Y194661D01*
X229148Y194995D01*
X229190Y195370D01*
X229148Y195703D01*
X228940Y196036D01*
X228690Y196245D01*
X228440Y196286D01*
X228148Y196203D01*
X227940Y195911D01*
X227857Y195620D01*
Y195245D01*
G01Y195620D02*
X227732Y195870D01*
X227523Y196078D01*
X227273Y196161D01*
X227023Y196078D01*
X226815Y195870D01*
X226690Y195495D01*
X226732Y195120D01*
X226898Y194745D01*
G01X228148Y197636D02*
X227857Y197928D01*
X227690Y198178D01*
X227607Y198511D01*
X227690Y198803D01*
X227857Y199011D01*
X228107Y199178D01*
X228398Y199220D01*
X228648Y199178D01*
X228898Y199011D01*
X229107Y198761D01*
X229190Y198470D01*
X229107Y198136D01*
X228857Y197845D01*
X228482Y197678D01*
X228065Y197636D01*
X227523Y197720D01*
X227232Y197845D01*
X226940Y198053D01*
X226732Y198345D01*
X226690Y198636D01*
X226773Y198928D01*
X226982Y199136D01*
G01X227132Y285136D02*
X224632D01*
Y286177D01*
X224757Y286511D01*
X224924Y286719D01*
X225257Y286802D01*
X225590Y286719D01*
X225799Y286469D01*
X225924Y286177D01*
Y285136D01*
G01Y286177D02*
X227132Y286802D01*
G01Y289069D02*
X224632D01*
X225132Y288569D01*
G01X227132D02*
Y289569D01*
G01Y292169D02*
X227090Y292461D01*
X226965Y292794D01*
X226757Y293002D01*
X226465Y293086D01*
X226174Y293002D01*
X225924Y292752D01*
X225799Y292377D01*
Y291961D01*
X225715Y291711D01*
X225507Y291502D01*
X225215Y291419D01*
X224924Y291544D01*
X224715Y291836D01*
X224632Y292169D01*
X224715Y292502D01*
X224924Y292794D01*
X225215Y292919D01*
X225507Y292836D01*
X225715Y292627D01*
X225799Y292377D01*
Y291961D01*
X225924Y291586D01*
X226174Y291336D01*
X226465Y291252D01*
X226757Y291336D01*
X226965Y291544D01*
X227090Y291877D01*
X227132Y292169D01*
G01X228064Y311544D02*
X225564D01*
Y312378D01*
X225689Y312711D01*
X225856Y312961D01*
X226106Y313169D01*
X226397Y313336D01*
X226814Y313378D01*
X227231Y313336D01*
X227522Y313169D01*
X227772Y312961D01*
X227939Y312711D01*
X228064Y312378D01*
Y311544D01*
G01Y315561D02*
X228022Y315853D01*
X227897Y316186D01*
X227689Y316394D01*
X227397Y316478D01*
X227106Y316394D01*
X226856Y316144D01*
X226731Y315769D01*
Y315353D01*
X226647Y315103D01*
X226439Y314894D01*
X226147Y314811D01*
X225856Y314936D01*
X225647Y315228D01*
X225564Y315561D01*
X225647Y315894D01*
X225856Y316186D01*
X226147Y316311D01*
X226439Y316228D01*
X226647Y316019D01*
X226731Y315769D01*
Y315353D01*
X226856Y314978D01*
X227106Y314728D01*
X227397Y314644D01*
X227689Y314728D01*
X227897Y314936D01*
X228022Y315269D01*
X228064Y315561D01*
G01X224289Y319231D02*
Y307531D01*
G01X285039Y372688D02*
Y364888D01*
X272439D01*
Y372688D01*
X285039D01*
G01X281539Y366288D02*
X282139Y366388D01*
X282639Y366888D01*
X283039Y367388D01*
X283239Y367988D01*
X283339Y368788D01*
X283239Y369488D01*
X283039Y370188D01*
X282639Y370688D01*
X282139Y371088D01*
X281539Y371288D01*
X280839Y371088D01*
X280339Y370688D01*
X280039Y370188D01*
X279739Y369488D01*
X279639Y368788D01*
X279739Y367988D01*
X280039Y367388D01*
X280339Y366888D01*
X280839Y366388D01*
X281539Y366288D01*
G01X274939Y371288D02*
Y366288D01*
X278039Y369888D01*
X273839D01*
G01X507367Y278643D02*
X507834Y279109D01*
X508234Y279376D01*
X508767Y279509D01*
X509234Y279376D01*
X509567Y279109D01*
X509834Y278709D01*
X509901Y278243D01*
X509834Y277843D01*
X509567Y277443D01*
X509167Y277109D01*
X508701Y276976D01*
X508167Y277109D01*
X507701Y277509D01*
X507434Y278109D01*
X507367Y278776D01*
X507501Y279643D01*
X507701Y280109D01*
X508034Y280576D01*
X508501Y280909D01*
X508967Y280976D01*
X509434Y280843D01*
X509767Y280509D01*
G01X507249Y307738D02*
X507649Y307405D01*
X508116Y307205D01*
X508716Y307138D01*
X509316Y307271D01*
X509783Y307538D01*
X510116Y308005D01*
X510183Y308538D01*
X510049Y309071D01*
X509716Y309405D01*
X509249Y309671D01*
X508783Y309738D01*
X508316Y309671D01*
X507716Y309405D01*
X507916Y311138D01*
X509716D01*
G01X509961Y339085D02*
Y343085D01*
X507494Y340218D01*
X510828D01*
G01X507457Y371403D02*
X507857Y370936D01*
X508391Y370670D01*
X508991Y370603D01*
X509524Y370670D01*
X510057Y371003D01*
X510391Y371403D01*
X510457Y371803D01*
X510324Y372270D01*
X509857Y372603D01*
X509391Y372736D01*
X508791D01*
G01X509391D02*
X509791Y372936D01*
X510124Y373270D01*
X510257Y373670D01*
X510124Y374070D01*
X509791Y374403D01*
X509191Y374603D01*
X508591Y374536D01*
X507991Y374270D01*
G01X507907Y405665D02*
X508307Y406065D01*
X508774Y406265D01*
X509307Y406332D01*
X509974Y406199D01*
X510441Y405865D01*
X510574Y405465D01*
X510507Y405065D01*
X510241Y404732D01*
X508907Y404065D01*
X508307Y403599D01*
X507907Y402932D01*
X507774Y402332D01*
X510574D01*
G01X508536Y433879D02*
Y437879D01*
X507736Y437079D01*
G01Y433879D02*
X509336D01*
G54D17*
G01X36609Y158938D02*
Y157838D01*
G01Y161638D02*
Y160538D01*
G01X19598Y156767D02*
Y152767D01*
G01X9597Y253079D02*
Y257079D01*
G01Y248327D02*
Y252327D01*
G01X9593Y243566D02*
Y247566D01*
G01X217520Y143500D02*
X213520D01*
G01X191583Y155700D02*
Y154600D01*
G01Y158400D02*
Y157300D01*
G01X184454Y286024D02*
X188454D01*
G01X189054D02*
X193054D01*
G01X193654D02*
X197654D01*
M02*
